# Altium SchDoc records: MAC.SchDoc
|HEADER=Protel for Windows - Schematic Capture Binary File Version 5.0|Weight=1377|MinorVersion=2
|RECORD=31|FontIdCount=9|Size1=10|FontName1=Times New Roman|Size2=10|Rotation2=90|FontName2=Times New Roman|Size3=12|FontName3=Arial|Size4=14|FontName4=Arial|Size5=24|FontName5=Times New Roman|Size6=10|Underline6=T|FontName6=Times New Roman|Size7=8|FontName7=Arial|Size8=10|FontName8=Arial|Size9=12|Underline9=T|FontName9=Arial|UseMBCS=T|IsBOC=T|HotSpotGridOn=T|HotSpotGridSize=1|SheetStyle=12|SystemFont=8|BorderOn=T|SheetNumberSpaceSize=12|AreaColor=16317695|SnapGridOn=T|SnapGridSize=1|VisibleGridOn=T|VisibleGridSize=10|CustomX=2338|CustomX_Frac=58268|CustomY=1653|CustomY_Frac=54331|CustomXZones=8|CustomYZones=6|CustomMarginWidth=19|CustomMarginWidth_Frac=80000|ShowTemplateGraphics=T|TemplateFileName=C:\Users\<user>\Documents\Altium\AD20\Templates\Timecard.SchDot|Display_Unit=0
|RECORD=39|IsNotAccesible=T|OwnerPartId=-1|FileName=C:\Users\<user>\Documents\Altium\AD20\Templates\Timecard.SchDot
|RECORD=4|OwnerIndex=1|OwnerPartId=-1|Location.X=1594|Location.Y=39|Color=8388608|FontID=9|Text=timingcard.com|URL=http://timingcard.com
|RECORD=6|OwnerIndex=1|IndexInSheet=1|OwnerPartId=-1|LocationCount=2|X1=1680|Y1=35|X2=1576|Y2=35
|RECORD=4|OwnerIndex=1|IndexInSheet=2|OwnerPartId=-1|Location.X=1614|Location.X_Frac=42446|Location.Y=19|Location.Y_Frac=96838|FontID=3|Text==SheetNumber
|RECORD=4|OwnerIndex=1|IndexInSheet=3|OwnerPartId=-1|Location.X=1581|Location.X_Frac=42446|Location.Y=29|Location.Y_Frac=96838|Justification=3|FontID=7|Text=SHEET
|RECORD=4|OwnerIndex=1|IndexInSheet=4|OwnerPartId=-1|Location.X=1639|Location.X_Frac=42446|Location.Y=29|Location.Y_Frac=96838|Justification=3|FontID=7|Text=OF
|RECORD=6|OwnerIndex=1|IndexInSheet=5|OwnerPartId=-1|LineWidth=1|LocationCount=2|X1=1679|X1_Frac=42446|Y1=105|Y1_Frac=96838|X2=1576|Y2=106
|RECORD=4|OwnerIndex=1|IndexInSheet=6|OwnerPartId=-1|Location.X=1658|Location.Y=20|FontID=3|Text==SheetTotal
|RECORD=30|OwnerIndex=1|IndexInSheet=7|OwnerPartId=-1|Location.X=1578|Location.Y=53|Corner.X=1673|Corner.X_Frac=88801|Corner.Y=103|KeepAspect=T|FileName=C:\Users\<user>\Desktop\Timecard Logo\TIMECARD.jpg
|RECORD=6|OwnerIndex=1|IndexInSheet=8|OwnerPartId=-1|LineWidth=1|LocationCount=2|X1=1576|X1_Frac=3162|Y1=105|Y1_Frac=42446|X2=1576|Y2=20
|RECORD=6|OwnerIndex=1|IndexInSheet=9|OwnerPartId=-1|LocationCount=2|X1=1680|Y1=51|X2=1576|Y2=51
|RECORD=41|IndexInSheet=1|OwnerPartId=-1|Color=8388608|FontID=1|IsHidden=T|Text=*|Name=CurrentTime|ReadOnlyState=1
|RECORD=41|IndexInSheet=2|OwnerPartId=-1|Color=8388608|FontID=1|IsHidden=T|Text=*|Name=CurrentDate|ReadOnlyState=1
|RECORD=41|IndexInSheet=3|OwnerPartId=-1|Color=8388608|FontID=1|IsHidden=T|Text=*|Name=Time|ReadOnlyState=1
|RECORD=41|IndexInSheet=4|OwnerPartId=-1|Color=8388608|FontID=1|IsHidden=T|Text=*|Name=Date|ReadOnlyState=1
|RECORD=41|IndexInSheet=5|OwnerPartId=-1|Color=8388608|FontID=1|IsHidden=T|Text=*|Name=DocumentFullPathAndName|ReadOnlyState=1
|RECORD=41|IndexInSheet=6|OwnerPartId=-1|Color=8388608|FontID=1|IsHidden=T|Text=*|Name=DocumentName|ReadOnlyState=1
|RECORD=41|IndexInSheet=7|OwnerPartId=-1|Color=8388608|FontID=1|IsHidden=T|Text=*|Name=ModifiedDate|ReadOnlyState=1
|RECORD=41|IndexInSheet=8|OwnerPartId=-1|Color=8388608|FontID=1|IsHidden=T|Text=*|Name=ApprovedBy|ReadOnlyState=1
|RECORD=41|IndexInSheet=9|OwnerPartId=-1|Color=8388608|FontID=1|IsHidden=T|Text=*|Name=CheckedBy|ReadOnlyState=1
|RECORD=41|IndexInSheet=10|OwnerPartId=-1|Color=8388608|FontID=1|IsHidden=T|Text=<name>|Name=Author|ReadOnlyState=1
|RECORD=41|IndexInSheet=11|OwnerPartId=-1|Color=8388608|FontID=1|IsHidden=T|Text=*|Name=CompanyName|ReadOnlyState=1
|RECORD=41|IndexInSheet=12|OwnerPartId=-1|Color=8388608|FontID=1|IsHidden=T|Text=*|Name=DrawnBy|ReadOnlyState=1
|RECORD=41|IndexInSheet=13|OwnerPartId=-1|Color=8388608|FontID=1|IsHidden=T|Text=*|Name=Engineer|ReadOnlyState=1
|RECORD=41|IndexInSheet=14|OwnerPartId=-1|Color=8388608|FontID=1|IsHidden=T|Text=*|Name=Organization|ReadOnlyState=1
|RECORD=41|IndexInSheet=15|OwnerPartId=-1|Color=8388608|FontID=1|IsHidden=T|Text=*|Name=Address1|ReadOnlyState=1
|RECORD=41|IndexInSheet=16|OwnerPartId=-1|Color=8388608|FontID=1|IsHidden=T|Text=*|Name=Address2|ReadOnlyState=1
|RECORD=41|IndexInSheet=17|OwnerPartId=-1|Color=8388608|FontID=1|IsHidden=T|Text=*|Name=Address3|ReadOnlyState=1
|RECORD=41|IndexInSheet=18|OwnerPartId=-1|Color=8388608|FontID=1|IsHidden=T|Text=*|Name=Address4|ReadOnlyState=1
|RECORD=41|IndexInSheet=19|OwnerPartId=-1|Color=8388608|FontID=1|IsHidden=T|Text=Grandmaster MAC & Clock Generation|Name=Title|ReadOnlyState=1
|RECORD=41|IndexInSheet=20|OwnerPartId=-1|Color=8388608|FontID=1|IsHidden=T|Text=*|Name=DocumentNumber|ReadOnlyState=1
|RECORD=41|IndexInSheet=21|OwnerPartId=-1|Color=8388608|FontID=1|IsHidden=T|Text=A|Name=Revision|ReadOnlyState=1
|RECORD=41|IndexInSheet=22|OwnerPartId=-1|Color=8388608|FontID=1|IsHidden=T|Text=6|Name=SheetNumber|ReadOnlyState=1
|RECORD=41|IndexInSheet=23|OwnerPartId=-1|Color=8388608|FontID=1|IsHidden=T|Text=7|Name=SheetTotal|ReadOnlyState=1
|RECORD=41|IndexInSheet=24|OwnerPartId=-1|Color=8388608|FontID=1|IsHidden=T|Text=*|Name=Rule|ReadOnlyState=1
|RECORD=41|IndexInSheet=25|OwnerPartId=-1|Color=8388608|FontID=1|IsHidden=T|Text=*|Name=ImagePath|ReadOnlyState=1
|RECORD=41|IndexInSheet=26|OwnerPartId=-1|Color=8388608|FontID=1|IsHidden=T|Text=*|Name=ProjectName|ReadOnlyState=1
|RECORD=41|IndexInSheet=27|OwnerPartId=-1|Color=8388608|FontID=1|IsHidden=T|Text=*|Name=Application_BuildNumber|ReadOnlyState=1
|RECORD=41|IndexInSheet=28|OwnerPartId=-1|Location.X=21474|Location.X_Frac=83647|Location.Y=21464|Location.Y_Frac=83647|Color=8388608|FontID=1|IsHidden=T|Text=01910|Name=Customer
|RECORD=41|IndexInSheet=29|OwnerPartId=-1|Location.X=1000|Location.Y=10|Color=8388608|FontID=1|IsHidden=T|Text=*|Name=DocStatus
|RECORD=17|IndexInSheet=30|OwnerPartId=-1|ShowNetName=T|Location.X=590|Location.Y=430|Color=255|FontID=1|Text=MAC_TX|IsCrossSheetConnector=T
|RECORD=17|IndexInSheet=31|OwnerPartId=-1|ShowNetName=T|Location.X=590|Location.Y=420|Color=255|FontID=1|Text=MAC_RX|IsCrossSheetConnector=T
|RECORD=17|IndexInSheet=32|OwnerPartId=-1|ShowNetName=T|Location.X=590|Location.Y=410|Color=255|FontID=1|Text=MAC_BITE|IsCrossSheetConnector=T
|RECORD=17|IndexInSheet=33|OwnerPartId=-1|ShowNetName=T|Location.X=290|Location.Y=410|Orientation=2|Color=255|FontID=1|Text=MAC_RF_OUT|IsCrossSheetConnector=T
|RECORD=17|IndexInSheet=34|OwnerPartId=-1|ShowNetName=T|Location.X=290|Location.Y=430|Orientation=2|Color=255|FontID=1|Text=MAC_FREQ_CTRL|IsCrossSheetConnector=T
|RECORD=17|IndexInSheet=35|OwnerPartId=-1|ShowNetName=T|Location.X=290|Location.Y=330|Orientation=2|Color=255|FontID=1|Text=MAC_PPS_IN1+|IsCrossSheetConnector=T
|RECORD=22|IndexInSheet=36|OwnerPartId=-1|Location.X=350|Location.Y=280|Color=255|Orientation=1|Symbol=Thin Cross|IsActive=T|SuppressAll=T
|RECORD=22|IndexInSheet=37|OwnerPartId=-1|Location.X=350|Location.Y=270|Color=255|Orientation=1|Symbol=Thin Cross|IsActive=T|SuppressAll=T
|RECORD=22|IndexInSheet=38|OwnerPartId=-1|Location.X=350|Location.Y=260|Color=255|Orientation=1|Symbol=Thin Cross|IsActive=T|SuppressAll=T
|RECORD=22|IndexInSheet=39|OwnerPartId=-1|Location.X=350|Location.Y=250|Color=255|Orientation=1|Symbol=Thin Cross|IsActive=T|SuppressAll=T
|RECORD=22|IndexInSheet=40|OwnerPartId=-1|Location.X=350|Location.Y=240|Color=255|Orientation=1|Symbol=Thin Cross|IsActive=T|SuppressAll=T
|RECORD=22|IndexInSheet=41|OwnerPartId=-1|Location.X=350|Location.Y=230|Color=255|Orientation=1|Symbol=Thin Cross|IsActive=T|SuppressAll=T
|RECORD=22|IndexInSheet=42|OwnerPartId=-1|Location.X=350|Location.Y=220|Color=255|Orientation=1|Symbol=Thin Cross|IsActive=T|SuppressAll=T
|RECORD=17|IndexInSheet=43|OwnerPartId=-1|ShowNetName=T|Location.X=290|Location.Y=320|Orientation=2|Color=255|FontID=1|Text=MAC_PPS_IN1-|IsCrossSheetConnector=T
|RECORD=17|IndexInSheet=44|OwnerPartId=-1|ShowNetName=T|Location.X=290|Location.Y=310|Orientation=2|Color=255|FontID=1|Text=MAC_PPS_IN0+|IsCrossSheetConnector=T
|RECORD=17|IndexInSheet=45|OwnerPartId=-1|ShowNetName=T|Location.X=290|Location.Y=300|Orientation=2|Color=255|FontID=1|Text=MAC_PPS_IN0-|IsCrossSheetConnector=T
|RECORD=17|IndexInSheet=46|OwnerPartId=-1|ShowNetName=T|Location.X=590|Location.Y=330|Color=255|FontID=1|Text=MAC_USB+|IsCrossSheetConnector=T
|RECORD=17|IndexInSheet=47|OwnerPartId=-1|ShowNetName=T|Location.X=590|Location.Y=320|Color=255|FontID=1|Text=MAC_USB-|IsCrossSheetConnector=T
|RECORD=17|IndexInSheet=48|OwnerPartId=-1|ShowNetName=T|Location.X=590|Location.Y=310|Color=255|FontID=1|Text=MAC_USB_PWR|IsCrossSheetConnector=T
|RECORD=17|IndexInSheet=49|OwnerPartId=-1|ShowNetName=T|Location.X=590|Location.Y=290|Color=255|FontID=1|Text=MAC_PPS_OUT+|IsCrossSheetConnector=T
|RECORD=17|IndexInSheet=50|OwnerPartId=-1|ShowNetName=T|Location.X=590|Location.Y=280|Color=255|FontID=1|Text=MAC_PPS_OUT-|IsCrossSheetConnector=T
|RECORD=17|IndexInSheet=51|OwnerPartId=-1|ShowNetName=T|Location.X=590|Location.Y=260|Color=255|FontID=1|Text=MAC_ALARM|IsCrossSheetConnector=T
|RECORD=17|IndexInSheet=52|OwnerPartId=-1|Style=4|ShowNetName=T|Location.X=550|Location.Y=210|Orientation=3|Color=128|FontID=1|Text=GND
|RECORD=17|IndexInSheet=53|OwnerPartId=-1|Style=4|ShowNetName=T|Location.X=320|Location.Y=380|Orientation=3|Color=128|FontID=1|Text=GND
|RECORD=17|IndexInSheet=54|OwnerPartId=-1|ShowNetName=T|Location.X=720|Location.Y=400|Orientation=1|Color=128|FontID=1|Text=+5.0V
|RECORD=17|IndexInSheet=55|OwnerPartId=-1|Style=4|ShowNetName=T|Location.X=720|Location.Y=350|Orientation=3|Color=128|FontID=1|Text=GND
|RECORD=4|IndexInSheet=56|OwnerPartId=-1|Location.X=420|Location.Y=480|Color=8388608|FontID=5|Text=MAC
|RECORD=1|LibReference=CAP_0805_10UF_25V|ComponentDescription=CAP, CER, 10.UF, 25V, 10%, X5R, 0805|PartCount=2|DisplayModeCount=1|IndexInSheet=57|OwnerPartId=-1|Location.X=650|Location.Y=340|CurrentPartId=1|LibraryPath=*|SourceLibraryName=Capacitors.IntLib|TargetFileName=*|AreaColor=11599871|Color=128|PartIDLocked=F|DesignItemId=CAP_0805_10UF_25V|AllPinCount=2
|RECORD=41|OwnerIndex=68|OwnerPartId=-1|Location.X=650|Location.Y=340|Color=8388608|FontID=3|IsHidden=T|Text=TAIYO YUDEN|Name=MFG NAME
|RECORD=41|OwnerIndex=68|IndexInSheet=1|OwnerPartId=-1|Location.X=650|Location.Y=340|Color=8388608|FontID=3|IsHidden=T|Text=TMK212BBJ106KG-T|Name=MFG PART NUM
|RECORD=41|OwnerIndex=68|IndexInSheet=2|OwnerPartId=-1|Location.X=650|Location.Y=340|Color=8388608|FontID=3|IsHidden=T|Text=10/23/2013|Name=MODIFY DATE
|RECORD=41|OwnerIndex=68|IndexInSheet=3|OwnerPartId=-1|Location.X=650|Location.Y=340|Color=8388608|FontID=3|IsHidden=T|Text=CAP, CER|Name=CATEGORY
|RECORD=41|OwnerIndex=68|IndexInSheet=4|OwnerPartId=-1|Location.X=648|Location.Y=352|Location.Y_Frac=50000|Color=8388608|FontID=3|IsHidden=T|Text=4/11/2006 3:37:28 PM|Name=Date
|RECORD=41|OwnerIndex=68|IndexInSheet=5|OwnerPartId=-1|Location.X=656|Location.Y=414|Location.Y_Frac=48252|Color=8388608|FontID=3|IsHidden=T|Text=*|Name=SHEETPART
|RECORD=41|OwnerIndex=68|IndexInSheet=6|OwnerPartId=-1|Location.X=656|Location.Y=414|Location.Y_Frac=48252|Color=8388608|FontID=3|IsHidden=T|Text=10%|Name=P1
|RECORD=41|OwnerIndex=68|IndexInSheet=7|OwnerPartId=-1|Location.X=656|Location.Y=414|Location.Y_Frac=48252|Color=8388608|FontID=3|IsHidden=T|Text=85C|Name=MAXTEMP
|RECORD=41|OwnerIndex=68|IndexInSheet=8|OwnerPartId=-1|Location.X=656|Location.Y=414|Location.Y_Frac=48252|Color=8388608|FontID=3|IsHidden=T|Text=-55C|Name=MINTEMP
|RECORD=41|OwnerIndex=68|IndexInSheet=9|OwnerPartId=-1|Location.X=656|Location.Y=414|Location.Y_Frac=48252|Color=8388608|FontID=3|IsHidden=T|Name=OTHER
|RECORD=41|OwnerIndex=68|IndexInSheet=10|OwnerPartId=-1|Location.X=656|Location.Y=414|Location.Y_Frac=48252|Color=8388608|FontID=3|IsHidden=T|Text=25V|Name=P2
|RECORD=41|OwnerIndex=68|IndexInSheet=11|OwnerPartId=-1|Location.X=656|Location.Y=414|Location.Y_Frac=48252|Color=8388608|FontID=3|IsHidden=T|Text=X5R|Name=P3
|RECORD=41|OwnerIndex=68|IndexInSheet=12|OwnerPartId=-1|Location.X=656|Location.Y=414|Location.Y_Frac=48252|Color=8388608|FontID=3|IsHidden=T|Text=0805|Name=Size
|RECORD=41|OwnerIndex=68|IndexInSheet=13|OwnerPartId=-1|Location.X=656|Location.Y=414|Location.Y_Frac=48252|Color=8388608|FontID=3|IsHidden=T|Name=SUB
|RECORD=41|OwnerIndex=68|IndexInSheet=14|OwnerPartId=-1|Location.X=656|Location.Y=414|Location.Y_Frac=48252|Color=8388608|FontID=1|IsHidden=T|Text=CAP, CER, 10.UF, 10V, 10%, X5R, 0805|Name=DESC
|RECORD=41|OwnerIndex=68|IndexInSheet=15|OwnerPartId=-1|Location.X=656|Location.Y=413|Location.Y_Frac=98252|Color=8388608|FontID=1|IsHidden=T|Text=MOUSER|Name=Supplier 1|ReadOnlyState=1
|RECORD=41|OwnerIndex=68|IndexInSheet=16|OwnerPartId=-1|Location.X=656|Location.Y=413|Location.Y_Frac=98252|Color=8388608|FontID=1|IsHidden=T|Text=963-TMK212BBJ106KG-T|Name=Supplier Part Number 1|ReadOnlyState=1
|RECORD=41|OwnerIndex=68|IndexInSheet=17|OwnerPartId=-1|Location.X=680|Location.Y=370|Color=8388608|FontID=3|Text=10uF|Name=VALUE
|RECORD=2|OwnerIndex=68|OwnerPartId=1|FormalType=1|Electrical=4|PinConglomerate=35|PinLength=10|Location.X=670|Location.Y=370|Name=2|Designator=2|SwapIdPin=2|SwapIDPart=1|PinPropagationDelay=0.000000E+000
|RECORD=2|OwnerIndex=68|OwnerPartId=1|FormalType=1|Electrical=4|PinConglomerate=33|PinLength=10|Location.X=670|Location.Y=380|Name=1|Designator=1|SwapIdPin=1|SwapIDPart=1|PinPropagationDelay=0.000000E+000
|RECORD=13|OwnerIndex=68|IsNotAccesible=T|IndexInSheet=20|OwnerPartId=1|Location.X=670|Location.Y=372|Location.Y_Frac=50000|Corner.X=670|Corner.Y=370|LineWidth=1|Color=16711680
|RECORD=13|OwnerIndex=68|IsNotAccesible=T|IndexInSheet=21|OwnerPartId=1|Location.X=670|Location.Y=380|Corner.X=670|Corner.Y=377|Corner.Y_Frac=50000|LineWidth=1|Color=16711680
|RECORD=13|OwnerIndex=68|IsNotAccesible=T|IndexInSheet=22|OwnerPartId=1|Location.X=675|Location.Y=372|Location.Y_Frac=50000|Corner.X=665|Corner.Y=372|Corner.Y_Frac=50000|LineWidth=1|Color=16711680
|RECORD=13|OwnerIndex=68|IsNotAccesible=T|IndexInSheet=23|OwnerPartId=1|Location.X=675|Location.Y=377|Location.Y_Frac=50000|Corner.X=665|Corner.Y=377|Corner.Y_Frac=50000|LineWidth=1|Color=16711680
|RECORD=41|OwnerIndex=68|IndexInSheet=24|OwnerPartId=-1|Location.X=656|Location.Y=413|Location.Y_Frac=98951|Color=8388608|FontID=1|IsHidden=T|Text=<VALENTIUM>|Name=VALENTIUM PART NUM
|RECORD=34|OwnerIndex=68|IndexInSheet=-1|OwnerPartId=-1|Location.X=680|Location.Y=380|Color=8388608|FontID=4|Text=C62|Name=Designator|ReadOnlyState=1
|RECORD=41|OwnerIndex=68|IndexInSheet=-1|OwnerPartId=-1|Location.X=677|Location.X_Frac=50000|Location.Y=335|Color=8388608|FontID=3|IsHidden=T|Text=CAP_0805_10UF_25V|Name=Comment
|RECORD=44|OwnerIndex=68
|RECORD=45|OwnerIndex=98|IndexInSheet=-1|Description=Chip Capacitor, 0805, 2-Leads, Body 2.00x1.25mm, IPC Medium Density|UseComponentLibrary=T|ModelName=CAPC2012X14N|ModelType=PCBLIB|DatafileCount=1|ModelDatafileEntity0=CAPC2012X14N|ModelDatafileKind0=PCBLib|IsCurrent=T|DatalinksLocked=T|DatabaseDatalinksLocked=T|IntegratedModel=T|DatabaseModel=T
|RECORD=46|OwnerIndex=99
|RECORD=48|OwnerIndex=99
|RECORD=1|LibReference=MAC-SA5X|ComponentDescription=MOD, MAC, MAC-SA5X, ATOMIC CLOCK|PartCount=3|DisplayModeCount=1|IndexInSheet=58|OwnerPartId=-1|Location.X=440|Location.Y=420|CurrentPartId=1|LibraryPath=*|SourceLibraryName=Modules.IntLib|TargetFileName=*|AreaColor=11599871|Color=128|PartIDLocked=F|DesignItemId=MAC-SA5X|AllPinCount=28
|RECORD=41|OwnerIndex=102|OwnerPartId=-1|Location.X=440|Location.Y=420|Color=8388608|FontID=3|IsHidden=T|Text=3/22/2006 1:36:44 PM|Name=MODIFY DATE
|RECORD=41|OwnerIndex=102|IndexInSheet=1|OwnerPartId=-1|Location.X=440|Location.Y=420|Color=8388608|FontID=3|IsHidden=T|Text=MAC-SA5X|Name=MFG PART NUM
|RECORD=41|OwnerIndex=102|IndexInSheet=2|OwnerPartId=-1|Location.X=408|Location.Y=452|Color=8388608|FontID=3|IsHidden=T|Text=MOD|Name=CATEGORY
|RECORD=41|OwnerIndex=102|IndexInSheet=3|OwnerPartId=-1|Location.X=408|Location.Y=452|Color=8388608|FontID=3|IsHidden=T|Name=DATE
|RECORD=41|OwnerIndex=102|IndexInSheet=4|OwnerPartId=-1|Location.X=408|Location.Y=452|Color=8388608|FontID=3|IsHidden=T|Text=MICROCHIP|Name=MFG NAME
|RECORD=41|OwnerIndex=102|IndexInSheet=5|OwnerPartId=-1|Location.X=408|Location.Y=452|Color=8388608|FontID=3|IsHidden=T|Text=85C|Name=MAXTEMP
|RECORD=41|OwnerIndex=102|IndexInSheet=6|OwnerPartId=-1|Location.X=408|Location.Y=452|Color=8388608|FontID=3|IsHidden=T|Text=-40C|Name=MINTEMP
|RECORD=41|OwnerIndex=102|IndexInSheet=7|OwnerPartId=-1|Location.X=408|Location.Y=452|Color=8388608|FontID=3|IsHidden=T|Text=AEC-Q200|Name=OTHER
|RECORD=41|OwnerIndex=102|IndexInSheet=8|OwnerPartId=-1|Location.X=408|Location.Y=452|Color=8388608|FontID=3|IsHidden=T|Text=ATOMIC CLOCK|Name=P1
|RECORD=41|OwnerIndex=102|IndexInSheet=9|OwnerPartId=-1|Location.X=408|Location.Y=452|Color=8388608|FontID=3|IsHidden=T|Name=P2
|RECORD=41|OwnerIndex=102|IndexInSheet=10|OwnerPartId=-1|Location.X=408|Location.Y=452|Color=8388608|FontID=3|IsHidden=T|Name=P3
|RECORD=41|OwnerIndex=102|IndexInSheet=11|OwnerPartId=-1|Location.X=408|Location.Y=452|Color=8388608|FontID=3|IsHidden=T|Name=SIZE
|RECORD=41|OwnerIndex=102|IndexInSheet=12|OwnerPartId=-1|Location.X=408|Location.Y=452|Color=8388608|FontID=3|IsHidden=T|Name=SUB
|RECORD=41|OwnerIndex=102|IndexInSheet=13|OwnerPartId=-1|Location.X=408|Location.Y=248|Color=8388608|FontID=1|IsHidden=T|Text=*|Name=SHEETPART
|RECORD=41|OwnerIndex=102|IndexInSheet=14|OwnerPartId=-1|Location.X=408|Location.Y=452|Color=8388608|FontID=1|IsHidden=T|Text=MOD, MAC, MAC-SA5X, ATOMIC CLOCK|Name=DESC
|RECORD=41|OwnerIndex=102|IndexInSheet=15|OwnerPartId=-1|Location.X=398|Location.Y=452|Color=8388608|FontID=1|IsHidden=T|Text=<V PART NUM>|Name=VELENTIUM PART NUM
|RECORD=14|OwnerIndex=102|IsNotAccesible=T|IndexInSheet=16|OwnerPartId=1|Location.X=370|Location.Y=390|Corner.X=520|Corner.Y=440|Color=128|AreaColor=11599871|IsSolid=T
|RECORD=2|OwnerIndex=102|OwnerPartId=1|FormalType=1|Electrical=4|PinConglomerate=58|PinLength=30|Location.X=370|Location.Y=430|Name=FREQ CTRL IN|Designator=P1|SwapIDPart=Ž&Ž||PinPropagationDelay=0.000000E+000
|RECORD=2|OwnerIndex=102|OwnerPartId=1|FormalType=1|Electrical=4|PinConglomerate=58|PinLength=30|Location.X=370|Location.Y=420|Name=GND (CASE)|Designator=P2|SwapIDPart=Ž&Ž||PinPropagationDelay=0.000000E+000
|RECORD=2|OwnerIndex=102|OwnerPartId=1|FormalType=1|Electrical=4|PinConglomerate=58|PinLength=30|Location.X=370|Location.Y=410|Name=RF OUT|Designator=P3|SwapIDPart=Ž&Ž||PinPropagationDelay=0.000000E+000
|RECORD=2|OwnerIndex=102|OwnerPartId=1|FormalType=1|Electrical=4|PinConglomerate=58|PinLength=30|Location.X=370|Location.Y=400|Name=GND (SUPPLY & SIGNAL)|Designator=P4|SwapIDPart=Ž&Ž||PinPropagationDelay=0.000000E+000
|RECORD=2|OwnerIndex=102|OwnerPartId=1|FormalType=1|Electrical=4|PinConglomerate=56|PinLength=30|Location.X=520|Location.Y=400|Name=VCC|Designator=P5|SwapIDPart=Ž&Ž||PinPropagationDelay=0.000000E+000
|RECORD=2|OwnerIndex=102|OwnerPartId=1|FormalType=1|Electrical=4|PinConglomerate=56|PinLength=30|Location.X=520|Location.Y=410|Name=BITE|Designator=P6|SwapIDPart=Ž&Ž||PinPropagationDelay=0.000000E+000
|RECORD=2|OwnerIndex=102|OwnerPartId=1|FormalType=1|Electrical=4|PinConglomerate=56|PinLength=30|Location.X=520|Location.Y=420|Name=RS-232 TX|Designator=P7|SwapIDPart=Ž&Ž||PinPropagationDelay=0.000000E+000
|RECORD=2|OwnerIndex=102|OwnerPartId=1|FormalType=1|Electrical=4|PinConglomerate=56|PinLength=30|Location.X=520|Location.Y=430|Name=RS-232 RX|Designator=P8|SwapIDPart=Ž&Ž||PinPropagationDelay=0.000000E+000
|RECORD=41|OwnerIndex=102|IndexInSheet=25|OwnerPartId=-1|Location.X=370|Location.Y=378|Color=8388608|FontID=3|Text=RV-3049-C3|Name=VALUE
|RECORD=14|OwnerIndex=102|IsNotAccesible=T|IndexInSheet=26|OwnerPartId=2|Location.X=380|Location.Y=350|Corner.X=500|Corner.Y=480|Color=128|AreaColor=11599871|IsSolid=T
|RECORD=2|OwnerIndex=102|OwnerPartId=2|FormalType=1|Electrical=4|PinConglomerate=58|PinLength=30|Location.X=380|Location.Y=470|Name=PPS-IN 1+|Designator=1|SwapIDPart=Ž&Ž||PinPropagationDelay=0.000000E+000
|RECORD=2|OwnerIndex=102|OwnerPartId=2|FormalType=1|Electrical=4|PinConglomerate=56|PinLength=30|Location.X=500|Location.Y=470|Name=USB DATA +|Designator=2|SwapIDPart=Ž&Ž||PinPropagationDelay=0.000000E+000
|RECORD=2|OwnerIndex=102|OwnerPartId=2|FormalType=1|Electrical=4|PinConglomerate=58|PinLength=30|Location.X=380|Location.Y=460|Name=PPS-IN 1-|Designator=3|SwapIDPart=Ž&Ž||PinPropagationDelay=0.000000E+000
|RECORD=2|OwnerIndex=102|OwnerPartId=2|FormalType=1|Electrical=4|PinConglomerate=56|PinLength=30|Location.X=500|Location.Y=460|Name=USB DATA -|Designator=4|SwapIDPart=Ž&Ž||PinPropagationDelay=0.000000E+000
|RECORD=2|OwnerIndex=102|OwnerPartId=2|FormalType=1|Electrical=4|PinConglomerate=58|PinLength=30|Location.X=380|Location.Y=450|Name=PPS-IN 0+|Designator=5|SwapIDPart=Ž&Ž||PinPropagationDelay=0.000000E+000
|RECORD=2|OwnerIndex=102|OwnerPartId=2|FormalType=1|Electrical=4|PinConglomerate=56|PinLength=30|Location.X=500|Location.Y=450|Name=USB POWER|Designator=6|SwapIDPart=Ž&Ž||PinPropagationDelay=0.000000E+000
|RECORD=2|OwnerIndex=102|OwnerPartId=2|FormalType=1|Electrical=4|PinConglomerate=58|PinLength=30|Location.X=380|Location.Y=440|Name=PPS-IN 0-|Designator=7|SwapIDPart=Ž&Ž||PinPropagationDelay=0.000000E+000
|RECORD=2|OwnerIndex=102|OwnerPartId=2|FormalType=1|Electrical=4|PinConglomerate=56|PinLength=30|Location.X=500|Location.Y=380|Name=GND|Designator=8|SwapIDPart=Ž&Ž||PinPropagationDelay=0.000000E+000
|RECORD=2|OwnerIndex=102|OwnerPartId=2|FormalType=1|Electrical=4|PinConglomerate=56|PinLength=30|Location.X=500|Location.Y=370|Name=GND|Designator=9|SwapIDPart=Ž&Ž||PinPropagationDelay=0.000000E+000
|RECORD=2|OwnerIndex=102|OwnerPartId=2|FormalType=1|Electrical=4|PinConglomerate=58|PinLength=30|Location.X=380|Location.Y=420|Name=NC|Designator=10|SwapIDPart=Ž&Ž||PinPropagationDelay=0.000000E+000
|RECORD=2|OwnerIndex=102|OwnerPartId=2|FormalType=1|Electrical=4|PinConglomerate=58|PinLength=30|Location.X=380|Location.Y=410|Name=NC|Designator=11|SwapIDPart=Ž&Ž||PinPropagationDelay=0.000000E+000
|RECORD=2|OwnerIndex=102|OwnerPartId=2|FormalType=1|Electrical=4|PinConglomerate=58|PinLength=30|Location.X=380|Location.Y=400|Name=NC|Designator=12|SwapIDPart=Ž&Ž||PinPropagationDelay=0.000000E+000
|RECORD=2|OwnerIndex=102|OwnerPartId=2|FormalType=1|Electrical=4|PinConglomerate=58|PinLength=30|Location.X=380|Location.Y=390|Name=NC|Designator=13|SwapIDPart=Ž&Ž||PinPropagationDelay=0.000000E+000
|RECORD=2|OwnerIndex=102|OwnerPartId=2|FormalType=1|Electrical=4|PinConglomerate=58|PinLength=30|Location.X=380|Location.Y=380|Name=NC|Designator=14|SwapIDPart=Ž&Ž||PinPropagationDelay=0.000000E+000
|RECORD=2|OwnerIndex=102|OwnerPartId=2|FormalType=1|Electrical=4|PinConglomerate=56|PinLength=30|Location.X=500|Location.Y=360|Name=GND|Designator=15|SwapIDPart=Ž&Ž||PinPropagationDelay=0.000000E+000
|RECORD=2|OwnerIndex=102|OwnerPartId=2|FormalType=1|Electrical=4|PinConglomerate=58|PinLength=30|Location.X=380|Location.Y=370|Name=NC|Designator=16|SwapIDPart=Ž&Ž||PinPropagationDelay=0.000000E+000
|RECORD=2|OwnerIndex=102|OwnerPartId=2|FormalType=1|Electrical=4|PinConglomerate=56|PinLength=30|Location.X=500|Location.Y=430|Name=PPS-OUT +|Designator=17|SwapIDPart=Ž&Ž||PinPropagationDelay=0.000000E+000
|RECORD=2|OwnerIndex=102|OwnerPartId=2|FormalType=1|Electrical=4|PinConglomerate=58|PinLength=30|Location.X=380|Location.Y=360|Name=NC|Designator=18|SwapIDPart=Ž&Ž||PinPropagationDelay=0.000000E+000
|RECORD=2|OwnerIndex=102|OwnerPartId=2|FormalType=1|Electrical=4|PinConglomerate=56|PinLength=30|Location.X=500|Location.Y=420|Name=PPS-OUT -|Designator=19|SwapIDPart=Ž&Ž||PinPropagationDelay=0.000000E+000
|RECORD=2|OwnerIndex=102|OwnerPartId=2|FormalType=1|Electrical=4|PinConglomerate=56|PinLength=30|Location.X=500|Location.Y=400|Name=ALARM|Designator=20|SwapIDPart=Ž&Ž||PinPropagationDelay=0.000000E+000
|RECORD=34|OwnerIndex=102|IndexInSheet=-1|OwnerPartId=-1|Location.X=370|Location.Y=440|Color=8388608|FontID=4|Text=U10|Name=Designator|ReadOnlyState=1
|RECORD=41|OwnerIndex=102|IndexInSheet=-1|OwnerPartId=-1|Location.X=460|Location.Y=380|Color=8388608|FontID=3|IsHidden=T|Text=="MFG PART NUM"|Name=Comment
|RECORD=44|OwnerIndex=102
|RECORD=45|OwnerIndex=180|IndexInSheet=-1|UseComponentLibrary=T|ModelName=MAC-SA5X|ModelType=PCBLIB|DatafileCount=1|ModelDatafileEntity0=MAC-SA5X|ModelDatafileKind0=PCBLib|IsCurrent=T|DatalinksLocked=T|DatabaseDatalinksLocked=T|IntegratedModel=T|DatabaseModel=T
|RECORD=46|OwnerIndex=181
|RECORD=48|OwnerIndex=181
|RECORD=1|LibReference=MAC-SA5X|ComponentDescription=MOD, MAC, MAC-SA5X, ATOMIC CLOCK|PartCount=3|DisplayModeCount=1|IndexInSheet=59|OwnerPartId=-1|Location.X=440|Location.Y=280|CurrentPartId=2|LibraryPath=*|SourceLibraryName=Modules.IntLib|TargetFileName=*|AreaColor=11599871|Color=128|PartIDLocked=F|DesignItemId=MAC-SA5X|AllPinCount=28
|RECORD=41|OwnerIndex=184|OwnerPartId=-1|Location.X=440|Location.Y=280|Color=8388608|FontID=3|IsHidden=T|Text=3/22/2006 1:36:44 PM|Name=MODIFY DATE
|RECORD=41|OwnerIndex=184|IndexInSheet=1|OwnerPartId=-1|Location.X=440|Location.Y=280|Color=8388608|FontID=3|IsHidden=T|Text=MAC-SA5X|Name=MFG PART NUM
|RECORD=41|OwnerIndex=184|IndexInSheet=2|OwnerPartId=-1|Location.X=408|Location.Y=312|Color=8388608|FontID=3|IsHidden=T|Text=MOD|Name=CATEGORY
|RECORD=41|OwnerIndex=184|IndexInSheet=3|OwnerPartId=-1|Location.X=408|Location.Y=312|Color=8388608|FontID=3|IsHidden=T|Name=DATE
|RECORD=41|OwnerIndex=184|IndexInSheet=4|OwnerPartId=-1|Location.X=408|Location.Y=312|Color=8388608|FontID=3|IsHidden=T|Text=MICROCHIP|Name=MFG NAME
|RECORD=41|OwnerIndex=184|IndexInSheet=5|OwnerPartId=-1|Location.X=408|Location.Y=312|Color=8388608|FontID=3|IsHidden=T|Text=85C|Name=MAXTEMP
|RECORD=41|OwnerIndex=184|IndexInSheet=6|OwnerPartId=-1|Location.X=408|Location.Y=312|Color=8388608|FontID=3|IsHidden=T|Text=-40C|Name=MINTEMP
|RECORD=41|OwnerIndex=184|IndexInSheet=7|OwnerPartId=-1|Location.X=408|Location.Y=312|Color=8388608|FontID=3|IsHidden=T|Text=AEC-Q200|Name=OTHER
|RECORD=41|OwnerIndex=184|IndexInSheet=8|OwnerPartId=-1|Location.X=408|Location.Y=312|Color=8388608|FontID=3|IsHidden=T|Text=ATOMIC CLOCK|Name=P1
|RECORD=41|OwnerIndex=184|IndexInSheet=9|OwnerPartId=-1|Location.X=408|Location.Y=312|Color=8388608|FontID=3|IsHidden=T|Name=P2
|RECORD=41|OwnerIndex=184|IndexInSheet=10|OwnerPartId=-1|Location.X=408|Location.Y=312|Color=8388608|FontID=3|IsHidden=T|Name=P3
|RECORD=41|OwnerIndex=184|IndexInSheet=11|OwnerPartId=-1|Location.X=408|Location.Y=312|Color=8388608|FontID=3|IsHidden=T|Name=SIZE
|RECORD=41|OwnerIndex=184|IndexInSheet=12|OwnerPartId=-1|Location.X=408|Location.Y=312|Color=8388608|FontID=3|IsHidden=T|Name=SUB
|RECORD=41|OwnerIndex=184|IndexInSheet=13|OwnerPartId=-1|Location.X=408|Location.Y=108|Color=8388608|FontID=1|IsHidden=T|Text=*|Name=SHEETPART
|RECORD=41|OwnerIndex=184|IndexInSheet=14|OwnerPartId=-1|Location.X=408|Location.Y=312|Color=8388608|FontID=1|IsHidden=T|Text=MOD, MAC, MAC-SA5X, ATOMIC CLOCK|Name=DESC
|RECORD=41|OwnerIndex=184|IndexInSheet=15|OwnerPartId=-1|Location.X=398|Location.Y=312|Color=8388608|FontID=1|IsHidden=T|Text=<V PART NUM>|Name=VELENTIUM PART NUM
|RECORD=14|OwnerIndex=184|IsNotAccesible=T|IndexInSheet=16|OwnerPartId=1|Location.X=370|Location.Y=250|Corner.X=520|Corner.Y=300|Color=128|AreaColor=11599871|IsSolid=T
|RECORD=2|OwnerIndex=184|OwnerPartId=1|FormalType=1|Electrical=4|PinConglomerate=58|PinLength=30|Location.X=370|Location.Y=290|Name=FREQ CTRL IN|Designator=P1|SwapIDPart=Ž&Ž||PinPropagationDelay=0.000000E+000
|RECORD=2|OwnerIndex=184|OwnerPartId=1|FormalType=1|Electrical=4|PinConglomerate=58|PinLength=30|Location.X=370|Location.Y=280|Name=GND (CASE)|Designator=P2|SwapIDPart=Ž&Ž||PinPropagationDelay=0.000000E+000
|RECORD=2|OwnerIndex=184|OwnerPartId=1|FormalType=1|Electrical=4|PinConglomerate=58|PinLength=30|Location.X=370|Location.Y=270|Name=RF OUT|Designator=P3|SwapIDPart=Ž&Ž||PinPropagationDelay=0.000000E+000
|RECORD=2|OwnerIndex=184|OwnerPartId=1|FormalType=1|Electrical=4|PinConglomerate=58|PinLength=30|Location.X=370|Location.Y=260|Name=GND (SUPPLY & SIGNAL)|Designator=P4|SwapIDPart=Ž&Ž||PinPropagationDelay=0.000000E+000
|RECORD=2|OwnerIndex=184|OwnerPartId=1|FormalType=1|Electrical=4|PinConglomerate=56|PinLength=30|Location.X=520|Location.Y=260|Name=VCC|Designator=P5|SwapIDPart=Ž&Ž||PinPropagationDelay=0.000000E+000
|RECORD=2|OwnerIndex=184|OwnerPartId=1|FormalType=1|Electrical=4|PinConglomerate=56|PinLength=30|Location.X=520|Location.Y=270|Name=BITE|Designator=P6|SwapIDPart=Ž&Ž||PinPropagationDelay=0.000000E+000
|RECORD=2|OwnerIndex=184|OwnerPartId=1|FormalType=1|Electrical=4|PinConglomerate=56|PinLength=30|Location.X=520|Location.Y=280|Name=RS-232 TX|Designator=P7|SwapIDPart=Ž&Ž||PinPropagationDelay=0.000000E+000
|RECORD=2|OwnerIndex=184|OwnerPartId=1|FormalType=1|Electrical=4|PinConglomerate=56|PinLength=30|Location.X=520|Location.Y=290|Name=RS-232 RX|Designator=P8|SwapIDPart=Ž&Ž||PinPropagationDelay=0.000000E+000
|RECORD=41|OwnerIndex=184|IndexInSheet=25|OwnerPartId=-1|Location.X=380|Location.Y=198|Color=8388608|FontID=3|Text=RV-3049-C3|Name=VALUE
|RECORD=14|OwnerIndex=184|IsNotAccesible=T|IndexInSheet=26|OwnerPartId=2|Location.X=380|Location.Y=210|Corner.X=500|Corner.Y=340|Color=128|AreaColor=11599871|IsSolid=T
|RECORD=2|OwnerIndex=184|OwnerPartId=2|FormalType=1|Electrical=4|PinConglomerate=58|PinLength=30|Location.X=380|Location.Y=330|Name=PPS-IN 1+|Designator=1|SwapIDPart=Ž&Ž||PinPropagationDelay=0.000000E+000
|RECORD=2|OwnerIndex=184|OwnerPartId=2|FormalType=1|Electrical=4|PinConglomerate=56|PinLength=30|Location.X=500|Location.Y=330|Name=USB DATA +|Designator=2|SwapIDPart=Ž&Ž||PinPropagationDelay=0.000000E+000
|RECORD=2|OwnerIndex=184|OwnerPartId=2|FormalType=1|Electrical=4|PinConglomerate=58|PinLength=30|Location.X=380|Location.Y=320|Name=PPS-IN 1-|Designator=3|SwapIDPart=Ž&Ž||PinPropagationDelay=0.000000E+000
|RECORD=2|OwnerIndex=184|OwnerPartId=2|FormalType=1|Electrical=4|PinConglomerate=56|PinLength=30|Location.X=500|Location.Y=320|Name=USB DATA -|Designator=4|SwapIDPart=Ž&Ž||PinPropagationDelay=0.000000E+000
|RECORD=2|OwnerIndex=184|OwnerPartId=2|FormalType=1|Electrical=4|PinConglomerate=58|PinLength=30|Location.X=380|Location.Y=310|Name=PPS-IN 0+|Designator=5|SwapIDPart=Ž&Ž||PinPropagationDelay=0.000000E+000
|RECORD=2|OwnerIndex=184|OwnerPartId=2|FormalType=1|Electrical=4|PinConglomerate=56|PinLength=30|Location.X=500|Location.Y=310|Name=USB POWER|Designator=6|SwapIDPart=Ž&Ž||PinPropagationDelay=0.000000E+000
|RECORD=2|OwnerIndex=184|OwnerPartId=2|FormalType=1|Electrical=4|PinConglomerate=58|PinLength=30|Location.X=380|Location.Y=300|Name=PPS-IN 0-|Designator=7|SwapIDPart=Ž&Ž||PinPropagationDelay=0.000000E+000
|RECORD=2|OwnerIndex=184|OwnerPartId=2|FormalType=1|Electrical=4|PinConglomerate=56|PinLength=30|Location.X=500|Location.Y=240|Name=GND|Designator=8|SwapIDPart=Ž&Ž||PinPropagationDelay=0.000000E+000
|RECORD=2|OwnerIndex=184|OwnerPartId=2|FormalType=1|Electrical=4|PinConglomerate=56|PinLength=30|Location.X=500|Location.Y=230|Name=GND|Designator=9|SwapIDPart=Ž&Ž||PinPropagationDelay=0.000000E+000
|RECORD=2|OwnerIndex=184|OwnerPartId=2|FormalType=1|Electrical=4|PinConglomerate=58|PinLength=30|Location.X=380|Location.Y=280|Name=NC|Designator=10|SwapIDPart=Ž&Ž||PinPropagationDelay=0.000000E+000
|RECORD=2|OwnerIndex=184|OwnerPartId=2|FormalType=1|Electrical=4|PinConglomerate=58|PinLength=30|Location.X=380|Location.Y=270|Name=NC|Designator=11|SwapIDPart=Ž&Ž||PinPropagationDelay=0.000000E+000
|RECORD=2|OwnerIndex=184|OwnerPartId=2|FormalType=1|Electrical=4|PinConglomerate=58|PinLength=30|Location.X=380|Location.Y=260|Name=NC|Designator=12|SwapIDPart=Ž&Ž||PinPropagationDelay=0.000000E+000
|RECORD=2|OwnerIndex=184|OwnerPartId=2|FormalType=1|Electrical=4|PinConglomerate=58|PinLength=30|Location.X=380|Location.Y=250|Name=NC|Designator=13|SwapIDPart=Ž&Ž||PinPropagationDelay=0.000000E+000
|RECORD=2|OwnerIndex=184|OwnerPartId=2|FormalType=1|Electrical=4|PinConglomerate=58|PinLength=30|Location.X=380|Location.Y=240|Name=NC|Designator=14|SwapIDPart=Ž&Ž||PinPropagationDelay=0.000000E+000
|RECORD=2|OwnerIndex=184|OwnerPartId=2|FormalType=1|Electrical=4|PinConglomerate=56|PinLength=30|Location.X=500|Location.Y=220|Name=GND|Designator=15|SwapIDPart=Ž&Ž||PinPropagationDelay=0.000000E+000
|RECORD=2|OwnerIndex=184|OwnerPartId=2|FormalType=1|Electrical=4|PinConglomerate=58|PinLength=30|Location.X=380|Location.Y=230|Name=NC|Designator=16|SwapIDPart=Ž&Ž||PinPropagationDelay=0.000000E+000
|RECORD=2|OwnerIndex=184|OwnerPartId=2|FormalType=1|Electrical=4|PinConglomerate=56|PinLength=30|Location.X=500|Location.Y=290|Name=PPS-OUT +|Designator=17|SwapIDPart=Ž&Ž||PinPropagationDelay=0.000000E+000
|RECORD=2|OwnerIndex=184|OwnerPartId=2|FormalType=1|Electrical=4|PinConglomerate=58|PinLength=30|Location.X=380|Location.Y=220|Name=NC|Designator=18|SwapIDPart=Ž&Ž||PinPropagationDelay=0.000000E+000
|RECORD=2|OwnerIndex=184|OwnerPartId=2|FormalType=1|Electrical=4|PinConglomerate=56|PinLength=30|Location.X=500|Location.Y=280|Name=PPS-OUT -|Designator=19|SwapIDPart=Ž&Ž||PinPropagationDelay=0.000000E+000
|RECORD=2|OwnerIndex=184|OwnerPartId=2|FormalType=1|Electrical=4|PinConglomerate=56|PinLength=30|Location.X=500|Location.Y=260|Name=ALARM|Designator=20|SwapIDPart=Ž&Ž||PinPropagationDelay=0.000000E+000
|RECORD=34|OwnerIndex=184|IndexInSheet=-1|OwnerPartId=-1|Location.X=380|Location.Y=340|Color=8388608|FontID=4|Text=U10|Name=Designator|ReadOnlyState=1
|RECORD=41|OwnerIndex=184|IndexInSheet=-1|OwnerPartId=-1|Location.X=460|Location.Y=240|Color=8388608|FontID=3|IsHidden=T|Text=="MFG PART NUM"|Name=Comment
|RECORD=44|OwnerIndex=184
|RECORD=45|OwnerIndex=262|IndexInSheet=-1|UseComponentLibrary=T|ModelName=MAC-SA5X|ModelType=PCBLIB|DatafileCount=1|ModelDatafileEntity0=MAC-SA5X|ModelDatafileKind0=PCBLib|IsCurrent=T|DatalinksLocked=T|DatabaseDatalinksLocked=T|IntegratedModel=T|DatabaseModel=T
|RECORD=46|OwnerIndex=263
|RECORD=48|OwnerIndex=263
|RECORD=17|IndexInSheet=60|OwnerPartId=-1|ShowNetName=T|Location.X=1330|Location.Y=630|Color=255|FontID=1|Text=DCXO2|IsCrossSheetConnector=T
|RECORD=17|IndexInSheet=61|OwnerPartId=-1|ShowNetName=T|Location.X=650|Location.Y=860|Color=255|FontID=1|Text=DCXO1|IsCrossSheetConnector=T
|RECORD=1|LibReference=CAP_0805_1UF_50V|ComponentDescription=CAP, CER, 1.0UF, 50V, 10%, X7R, 0805|PartCount=2|DisplayModeCount=1|IndexInSheet=62|OwnerPartId=-1|Location.X=1240|Location.Y=720|Orientation=2|CurrentPartId=1|LibraryPath=*|SourceLibraryName=Capacitors.IntLib|TargetFileName=*|AreaColor=11599871|Color=128|PartIDLocked=F|DesignItemId=CAP_0805_1UF_50V|AllPinCount=2
|RECORD=41|OwnerIndex=268|OwnerPartId=-1|Location.X=1214|Location.Y=702|Color=8388608|FontID=3|IsHidden=T|Text=MURATA|Name=MFG NAME
|RECORD=41|OwnerIndex=268|IndexInSheet=1|OwnerPartId=-1|Location.X=1214|Location.Y=702|Color=8388608|FontID=3|IsHidden=T|Text=GCM21BR71H105KA03L|Name=MFG PART NUM
|RECORD=41|OwnerIndex=268|IndexInSheet=2|OwnerPartId=-1|Location.X=1214|Location.Y=702|Color=8388608|FontID=3|IsHidden=T|Text=10/23/2013|Name=MODIFY DATE
|RECORD=41|OwnerIndex=268|IndexInSheet=3|OwnerPartId=-1|Location.X=1214|Location.Y=702|Color=8388608|FontID=3|IsHidden=T|Text=CAP, CER|Name=CATEGORY
|RECORD=41|OwnerIndex=268|IndexInSheet=4|OwnerPartId=-1|Location.X=1214|Location.Y=702|Color=8388608|FontID=3|IsHidden=T|Text=10/31/2006 2:46:38 PM|Name=Date
|RECORD=41|OwnerIndex=268|IndexInSheet=5|OwnerPartId=-1|Location.X=1214|Location.Y=702|Color=8388608|FontID=3|IsHidden=T|Text=*|Name=SHEETPART
|RECORD=41|OwnerIndex=268|IndexInSheet=6|OwnerPartId=-1|Location.X=1214|Location.Y=702|Color=8388608|FontID=3|IsHidden=T|Text=10%|Name=P1
|RECORD=41|OwnerIndex=268|IndexInSheet=7|OwnerPartId=-1|Location.X=1214|Location.Y=702|Color=8388608|FontID=3|IsHidden=T|Text=125C|Name=MAXTEMP
|RECORD=41|OwnerIndex=268|IndexInSheet=8|OwnerPartId=-1|Location.X=1214|Location.Y=702|Color=8388608|FontID=3|IsHidden=T|Text=-55C|Name=MINTEMP
|RECORD=41|OwnerIndex=268|IndexInSheet=9|OwnerPartId=-1|Location.X=1214|Location.Y=702|Color=8388608|FontID=3|IsHidden=T|Text=AEC-Q200|Name=OTHER
|RECORD=41|OwnerIndex=268|IndexInSheet=10|OwnerPartId=-1|Location.X=1214|Location.Y=702|Color=8388608|FontID=3|IsHidden=T|Text=50V|Name=P2
|RECORD=41|OwnerIndex=268|IndexInSheet=11|OwnerPartId=-1|Location.X=1214|Location.Y=702|Color=8388608|FontID=3|IsHidden=T|Text=X7R|Name=P3
|RECORD=41|OwnerIndex=268|IndexInSheet=12|OwnerPartId=-1|Location.X=1214|Location.Y=702|Color=8388608|FontID=3|IsHidden=T|Text=0805|Name=Size
|RECORD=41|OwnerIndex=268|IndexInSheet=13|OwnerPartId=-1|Location.X=1214|Location.Y=702|Color=8388608|FontID=3|IsHidden=T|Name=SUB
|RECORD=41|OwnerIndex=268|IndexInSheet=14|OwnerPartId=-1|Location.X=1214|Location.Y=702|Color=8388608|FontID=1|IsHidden=T|Text=CAP, CER, 1.0UF, 50V, 10%, X7R, 0805|Name=DESC
|RECORD=41|OwnerIndex=268|IndexInSheet=15|OwnerPartId=-1|Location.X=1214|Location.Y=702|Color=8388608|FontID=1|IsHidden=T|Text=Digi-Key|Name=Supplier 1|ReadOnlyState=3
|RECORD=41|OwnerIndex=268|IndexInSheet=16|OwnerPartId=-1|Location.X=1214|Location.Y=702|Color=8388608|FontID=1|IsHidden=T|Text=490-10675-1-ND|Name=Supplier Part Number 1|ReadOnlyState=3
|RECORD=41|OwnerIndex=268|IndexInSheet=17|OwnerPartId=-1|Location.X=1226|Location.Y=665|Color=8388608|FontID=3|Text=1.0UF|Name=VALUE
|RECORD=2|OwnerIndex=268|OwnerPartId=1|FormalType=1|Electrical=4|PinConglomerate=33|PinLength=10|Location.X=1220|Location.Y=690|Name=2|Designator=2|SwapIdPin=2|SwapIDPart=1|PinPropagationDelay=0.000000E+000
|RECORD=2|OwnerIndex=268|OwnerPartId=1|FormalType=1|Electrical=4|PinConglomerate=35|PinLength=10|Location.X=1220|Location.Y=680|Name=1|Designator=1|SwapIdPin=1|SwapIDPart=1|PinPropagationDelay=0.000000E+000
|RECORD=13|OwnerIndex=268|IsNotAccesible=T|IndexInSheet=20|OwnerPartId=1|Location.X=1220|Location.Y=687|Location.Y_Frac=50000|Corner.X=1220|Corner.Y=690|LineWidth=1|Color=16711680
|RECORD=13|OwnerIndex=268|IsNotAccesible=T|IndexInSheet=21|OwnerPartId=1|Location.X=1220|Location.Y=680|Corner.X=1220|Corner.Y=682|Corner.Y_Frac=50000|LineWidth=1|Color=16711680
|RECORD=13|OwnerIndex=268|IsNotAccesible=T|IndexInSheet=22|OwnerPartId=1|Location.X=1215|Location.Y=687|Location.Y_Frac=50000|Corner.X=1225|Corner.Y=687|Corner.Y_Frac=50000|LineWidth=1|Color=16711680
|RECORD=13|OwnerIndex=268|IsNotAccesible=T|IndexInSheet=23|OwnerPartId=1|Location.X=1215|Location.Y=682|Location.Y_Frac=50000|Corner.X=1225|Corner.Y=682|Corner.Y_Frac=50000|LineWidth=1|Color=16711680
|RECORD=41|OwnerIndex=268|IndexInSheet=24|OwnerPartId=-1|Location.X=1214|Location.Y=702|Color=8388608|FontID=1|IsHidden=T|Text=<VALENTIUM>|Name=VALENTIUM PART NUM
|RECORD=34|OwnerIndex=268|IndexInSheet=-1|OwnerPartId=-1|Location.X=1226|Location.Y=677|Color=8388608|FontID=4|Text=C65|Name=Designator|ReadOnlyState=1
|RECORD=41|OwnerIndex=268|IndexInSheet=-1|OwnerPartId=-1|Location.X=1214|Location.Y=702|Color=8388608|FontID=3|IsHidden=T|Text=CAP_0805_1UF_50V|Name=Comment
|RECORD=44|OwnerIndex=268
|RECORD=45|OwnerIndex=298|IndexInSheet=-1|Description=Chip Capacitor, 0805, 2-Leads, Body 2.00x1.25mm, IPC Medium Density|UseComponentLibrary=T|ModelName=CAPC2012X14N|ModelType=PCBLIB|DatafileCount=1|ModelDatafileEntity0=CAPC2012X14N|ModelDatafileKind0=PCBLib|IsCurrent=T|DatalinksLocked=T|DatabaseDatalinksLocked=T|IntegratedModel=T|DatabaseModel=T
|RECORD=46|OwnerIndex=299
|RECORD=48|OwnerIndex=299
|RECORD=1|LibReference=CAP_0603_0.01UF_50V|ComponentDescription=CAP, CER, 0.01UF, 50V, 10%, X7R, 0603|PartCount=2|DisplayModeCount=1|IndexInSheet=63|OwnerPartId=-1|Location.X=1320|Location.Y=720|Orientation=2|CurrentPartId=1|LibraryPath=*|SourceLibraryName=Capacitors.IntLib|TargetFileName=*|AreaColor=11599871|Color=128|PartIDLocked=F|DesignItemId=CAP_0603_0.01UF_50V|AllPinCount=2
|RECORD=41|OwnerIndex=302|OwnerPartId=-1|Location.X=1294|Location.Y=702|Color=8388608|FontID=3|IsHidden=T|Text=CAP, CER|Name=CATEGORY
|RECORD=41|OwnerIndex=302|IndexInSheet=1|OwnerPartId=-1|Location.X=1294|Location.Y=702|Color=8388608|FontID=3|IsHidden=T|Text=KEMET|Name=MFG NAME
|RECORD=41|OwnerIndex=302|IndexInSheet=2|OwnerPartId=-1|Location.X=1294|Location.Y=702|Color=8388608|FontID=3|IsHidden=T|Text=C0603C103K5RACTU|Name=MFG PART NUM
|RECORD=41|OwnerIndex=302|IndexInSheet=3|OwnerPartId=-1|Location.X=1294|Location.Y=702|Color=8388608|FontID=3|IsHidden=T|Text=10/23/2013|Name=MODIFY DATE
|RECORD=41|OwnerIndex=302|IndexInSheet=4|OwnerPartId=-1|Location.X=1294|Location.Y=702|Color=8388608|FontID=3|IsHidden=T|Text=7/24/2013|Name=Date
|RECORD=41|OwnerIndex=302|IndexInSheet=5|OwnerPartId=-1|Location.X=1294|Location.Y=702|Color=8388608|FontID=3|IsHidden=T|Text=*|Name=SHEETPART
|RECORD=41|OwnerIndex=302|IndexInSheet=6|OwnerPartId=-1|Location.X=1294|Location.Y=702|Color=8388608|FontID=3|IsHidden=T|Text=10%|Name=P1
|RECORD=41|OwnerIndex=302|IndexInSheet=7|OwnerPartId=-1|Location.X=1294|Location.Y=702|Color=8388608|FontID=3|IsHidden=T|Text=125C|Name=MAXTEMP
|RECORD=41|OwnerIndex=302|IndexInSheet=8|OwnerPartId=-1|Location.X=1294|Location.Y=702|Color=8388608|FontID=3|IsHidden=T|Text=-55C|Name=MINTEMP
|RECORD=41|OwnerIndex=302|IndexInSheet=9|OwnerPartId=-1|Location.X=1294|Location.Y=702|Color=8388608|FontID=3|IsHidden=T|Name=OTHER
|RECORD=41|OwnerIndex=302|IndexInSheet=10|OwnerPartId=-1|Location.X=1294|Location.Y=702|Color=8388608|FontID=3|IsHidden=T|Text=50V|Name=P2
|RECORD=41|OwnerIndex=302|IndexInSheet=11|OwnerPartId=-1|Location.X=1294|Location.Y=702|Color=8388608|FontID=3|IsHidden=T|Text=X7R|Name=P3
|RECORD=41|OwnerIndex=302|IndexInSheet=12|OwnerPartId=-1|Location.X=1294|Location.Y=702|Color=8388608|FontID=3|IsHidden=T|Text=0603|Name=Size
|RECORD=41|OwnerIndex=302|IndexInSheet=13|OwnerPartId=-1|Location.X=1294|Location.Y=702|Color=8388608|FontID=3|IsHidden=T|Name=SUB
|RECORD=41|OwnerIndex=302|IndexInSheet=14|OwnerPartId=-1|Location.X=1294|Location.Y=702|Color=8388608|FontID=3|IsHidden=T|Text=Digi-Key|Name=Supplier 1|ReadOnlyState=3
|RECORD=41|OwnerIndex=302|IndexInSheet=15|OwnerPartId=-1|Location.X=1294|Location.Y=702|Color=8388608|FontID=3|IsHidden=T|Text=399-1091-1-ND|Name=Supplier Part Number 1|ReadOnlyState=3
|RECORD=41|OwnerIndex=302|IndexInSheet=16|OwnerPartId=-1|Location.X=1294|Location.Y=702|Color=8388608|FontID=1|IsHidden=T|Text=CAP, CER, 0.01UF, 50V, 10%, X7R, 0603|Name=DESC
|RECORD=41|OwnerIndex=302|IndexInSheet=17|OwnerPartId=-1|Location.X=1306|Location.Y=665|Color=8388608|FontID=3|Text=0.01uF|Name=VALUE
|RECORD=2|OwnerIndex=302|OwnerPartId=1|FormalType=1|Electrical=4|PinConglomerate=33|PinLength=10|Location.X=1300|Location.Y=690|Name=2|Designator=2|SwapIdPin=2|SwapIDPart=1|PinPropagationDelay=0.000000E+000
|RECORD=2|OwnerIndex=302|OwnerPartId=1|FormalType=1|Electrical=4|PinConglomerate=35|PinLength=10|Location.X=1300|Location.Y=680|Name=1|Designator=1|SwapIdPin=1|SwapIDPart=1|PinPropagationDelay=0.000000E+000
|RECORD=13|OwnerIndex=302|IsNotAccesible=T|IndexInSheet=20|OwnerPartId=1|Location.X=1300|Location.Y=687|Location.Y_Frac=50000|Corner.X=1300|Corner.Y=690|LineWidth=1|Color=16711680
|RECORD=13|OwnerIndex=302|IsNotAccesible=T|IndexInSheet=21|OwnerPartId=1|Location.X=1300|Location.Y=680|Corner.X=1300|Corner.Y=682|Corner.Y_Frac=50000|LineWidth=1|Color=16711680
|RECORD=13|OwnerIndex=302|IsNotAccesible=T|IndexInSheet=22|OwnerPartId=1|Location.X=1295|Location.Y=687|Location.Y_Frac=50000|Corner.X=1305|Corner.Y=687|Corner.Y_Frac=50000|LineWidth=1|Color=16711680
|RECORD=13|OwnerIndex=302|IsNotAccesible=T|IndexInSheet=23|OwnerPartId=1|Location.X=1295|Location.Y=682|Location.Y_Frac=50000|Corner.X=1305|Corner.Y=682|Corner.Y_Frac=50000|LineWidth=1|Color=16711680
|RECORD=41|OwnerIndex=302|IndexInSheet=24|OwnerPartId=-1|Location.X=1294|Location.Y=702|Color=8388608|FontID=1|IsHidden=T|Text=<VALENTIUM>|Name=VALENTIUM PART NUM
|RECORD=34|OwnerIndex=302|IndexInSheet=-1|OwnerPartId=-1|Location.X=1306|Location.Y=677|Color=8388608|FontID=4|Text=C67|Name=Designator|ReadOnlyState=1
|RECORD=41|OwnerIndex=302|IndexInSheet=-1|OwnerPartId=-1|Location.X=1294|Location.Y=702|Color=8388608|FontID=3|IsHidden=T|Text=CAP_0603_0.01UF_50V|Name=Comment|ReadOnlyState=1
|RECORD=44|OwnerIndex=302
|RECORD=45|OwnerIndex=332|IndexInSheet=-1|Description=Chip Capacitor, 0603, 2-Leads, Body 1.60x0.80mm, IPC Medium Density|UseComponentLibrary=T|ModelName=CAPC1608X10N|ModelType=PCBLIB|DatafileCount=1|ModelDatafileEntity0=CAPC1608X10N|ModelDatafileKind0=PCBLib|IsCurrent=T|DatalinksLocked=T|DatabaseDatalinksLocked=T|IntegratedModel=T|DatabaseModel=T
|RECORD=46|OwnerIndex=333
|RECORD=48|OwnerIndex=333
|RECORD=1|LibReference=MPZ1608_220OHM_0603|ComponentDescription=FER, 220 OHM, 100MHZ, 2.2A, 0.05OHM DC, MPZ1608, 0603|PartCount=2|DisplayModeCount=1|IndexInSheet=64|OwnerPartId=-1|Location.X=1210|Location.Y=400|CurrentPartId=1|LibraryPath=*|SourceLibraryName=Passives.IntLib|TargetFileName=*|AreaColor=11599871|Color=128|PartIDLocked=F|DesignItemId=MPZ1608_220OHM_0603|AllPinCount=2
|RECORD=41|OwnerIndex=336|OwnerPartId=-1|Location.X=1210|Location.Y=400|Color=8388608|FontID=3|IsHidden=T|Text=MPZ1608S221ATA00|Name=MFG PART NUM
|RECORD=41|OwnerIndex=336|IndexInSheet=1|OwnerPartId=-1|Location.X=1210|Location.Y=400|Color=8388608|FontID=3|IsHidden=T|Text=9/4/2013|Name=MODIFY DATE
|RECORD=41|OwnerIndex=336|IndexInSheet=2|OwnerPartId=-1|Location.X=1210|Location.Y=400|Color=8388608|FontID=3|IsHidden=T|Text=TDK CORP|Name=MFG NAME
|RECORD=41|OwnerIndex=336|IndexInSheet=3|OwnerPartId=-1|Location.X=1210|Location.Y=400|Color=8388608|FontID=3|IsHidden=T|Text=FERRITE|Name=CATEGORY
|RECORD=41|OwnerIndex=336|IndexInSheet=4|OwnerPartId=-1|Location.X=1208|Location.Y=420|Color=8388608|FontID=3|IsHidden=T|Text=8/6/2013|Name=Date
|RECORD=41|OwnerIndex=336|IndexInSheet=5|OwnerPartId=-1|Location.X=1208|Location.Y=426|Color=8388608|FontID=3|IsHidden=T|Text=125C|Name=MAXTEMP
|RECORD=41|OwnerIndex=336|IndexInSheet=6|OwnerPartId=-1|Location.X=1208|Location.Y=426|Color=8388608|FontID=3|IsHidden=T|Text=-55C|Name=MINTEMP
|RECORD=41|OwnerIndex=336|IndexInSheet=7|OwnerPartId=-1|Location.X=1208|Location.Y=426|Color=8388608|FontID=3|IsHidden=T|Text=100MHZ|Name=P1
|RECORD=41|OwnerIndex=336|IndexInSheet=8|OwnerPartId=-1|Location.X=1208|Location.Y=426|Color=8388608|FontID=3|IsHidden=T|Text=2.2A|Name=P2
|RECORD=41|OwnerIndex=336|IndexInSheet=9|OwnerPartId=-1|Location.X=1208|Location.Y=426|Color=8388608|FontID=3|IsHidden=T|Text=0.05 OHM|Name=P3
|RECORD=41|OwnerIndex=336|IndexInSheet=10|OwnerPartId=-1|Location.X=1208|Location.Y=426|Color=8388608|FontID=3|IsHidden=T|Name=SUB
|RECORD=41|OwnerIndex=336|IndexInSheet=11|OwnerPartId=-1|Location.X=1208|Location.Y=426|Color=8388608|FontID=3|IsHidden=T|Text=0603|Name=SIZE
|RECORD=41|OwnerIndex=336|IndexInSheet=12|OwnerPartId=-1|Location.X=1208|Location.Y=380|Color=8388608|FontID=1|IsHidden=T|Text=*|Name=SHEETPART
|RECORD=41|OwnerIndex=336|IndexInSheet=13|OwnerPartId=-1|Location.X=1208|Location.Y=430|Color=8388608|FontID=1|IsHidden=T|Text=FER, 220 OHM, 100MHZ, 2.2A, 0.05OHM DC, MPZ1608, 0603|Name=DESC
|RECORD=41|OwnerIndex=336|IndexInSheet=14|OwnerPartId=-1|Location.X=1208|Location.Y=426|Color=8388608|FontID=3|IsHidden=T|Text=MPZ1608|Name=OTHER
|RECORD=41|OwnerIndex=336|IndexInSheet=15|OwnerPartId=-1|Location.X=1208|Location.Y=430|Color=8388608|FontID=1|IsHidden=T|Text=<VALENTIUM>|Name=VALENTIUM PART NUM
|RECORD=41|OwnerIndex=336|IndexInSheet=16|OwnerPartId=-1|Location.X=1208|Location.Y=430|Color=8388608|FontID=1|IsHidden=T|Text=Digi-Key|Name=Supplier 1|ReadOnlyState=3
|RECORD=41|OwnerIndex=336|IndexInSheet=17|OwnerPartId=-1|Location.X=1219|Location.Y=378|Color=8388608|FontID=3|Text=220 OHM|Name=VALUE
|RECORD=2|OwnerIndex=336|OwnerPartId=1|FormalType=1|Electrical=4|PinConglomerate=34|PinLength=10|Location.X=1220|Location.Y=400|Name=1|Designator=1|PinPropagationDelay=0.000000E+000
|RECORD=2|OwnerIndex=336|OwnerPartId=1|FormalType=1|Electrical=4|PinConglomerate=32|PinLength=10|Location.X=1260|Location.Y=400|Name=2|Designator=2|PinPropagationDelay=0.000000E+000
|RECORD=12|OwnerIndex=336|IsNotAccesible=T|IndexInSheet=20|OwnerPartId=1|Location.X=1250|Location.Y=400|Radius=5|LineWidth=1|EndAngle=180.000|Color=16711680
|RECORD=12|OwnerIndex=336|IsNotAccesible=T|IndexInSheet=21|OwnerPartId=1|Location.X=1240|Location.Y=400|Radius=5|LineWidth=1|EndAngle=180.000|Color=16711680
|RECORD=12|OwnerIndex=336|IsNotAccesible=T|IndexInSheet=22|OwnerPartId=1|Location.X=1230|Location.Y=400|Radius=5|LineWidth=1|EndAngle=178.662|Color=16711680
|RECORD=13|OwnerIndex=336|IsNotAccesible=T|IndexInSheet=23|OwnerPartId=1|Location.X=1220|Location.Y=400|Corner.X=1225|Corner.Y=400|LineWidth=1|Color=16711680
|RECORD=13|OwnerIndex=336|IsNotAccesible=T|IndexInSheet=24|OwnerPartId=1|Location.X=1255|Location.Y=400|Corner.X=1260|Corner.Y=400|LineWidth=1|Color=16711680
|RECORD=14|OwnerIndex=336|IsNotAccesible=T|IndexInSheet=25|OwnerPartId=1|Location.X=1220|Location.Y=390|Corner.X=1260|Corner.Y=410|LineWidth=1|AreaColor=16777215|IsSolid=T|Transparent=T
|RECORD=41|OwnerIndex=336|IndexInSheet=26|OwnerPartId=-1|Location.X=1219|Location.Y=368|Color=8388608|FontID=1|Text=445-1565-1-ND|Name=Supplier Part Number 1|ReadOnlyState=3
|RECORD=34|OwnerIndex=336|IndexInSheet=-1|OwnerPartId=-1|Location.X=1219|Location.Y=410|Color=8388608|FontID=4|Text=FB3|Name=Designator|ReadOnlyState=1
|RECORD=41|OwnerIndex=336|IndexInSheet=-1|OwnerPartId=-1|Location.X=1221|Location.Y=417|Color=8388608|FontID=3|IsHidden=T|Text=MPZ1608_220OHM_0603|Name=Comment|ReadOnlyState=1
|RECORD=44|OwnerIndex=336
|RECORD=45|OwnerIndex=368|IndexInSheet=-1|Description=Chip Inductor, 2-Leads, Body 1.60x0.80mm, IPC Medium Density|UseComponentLibrary=T|ModelName=INDC1608X09N|ModelType=PCBLIB|DatafileCount=1|ModelDatafileEntity0=INDC1608X09N|ModelDatafileKind0=PCBLib|IsCurrent=T|DatalinksLocked=T|DatabaseDatalinksLocked=T|IntegratedModel=T|DatabaseModel=T
|RECORD=46|OwnerIndex=369
|RECORD=48|OwnerIndex=369
|RECORD=1|LibReference=MPZ1608_220OHM_0603|ComponentDescription=FER, 220 OHM, 100MHZ, 2.2A, 0.05OHM DC, MPZ1608, 0603|PartCount=2|DisplayModeCount=1|IndexInSheet=65|OwnerPartId=-1|Location.X=1060|Location.Y=400|CurrentPartId=1|LibraryPath=*|SourceLibraryName=Passives.IntLib|TargetFileName=*|AreaColor=11599871|Color=128|PartIDLocked=F|DesignItemId=MPZ1608_220OHM_0603|AllPinCount=2
|RECORD=41|OwnerIndex=372|OwnerPartId=-1|Location.X=1060|Location.Y=400|Color=8388608|FontID=3|IsHidden=T|Text=MPZ1608S221ATA00|Name=MFG PART NUM
|RECORD=41|OwnerIndex=372|IndexInSheet=1|OwnerPartId=-1|Location.X=1060|Location.Y=400|Color=8388608|FontID=3|IsHidden=T|Text=9/4/2013|Name=MODIFY DATE
|RECORD=41|OwnerIndex=372|IndexInSheet=2|OwnerPartId=-1|Location.X=1060|Location.Y=400|Color=8388608|FontID=3|IsHidden=T|Text=TDK CORP|Name=MFG NAME
|RECORD=41|OwnerIndex=372|IndexInSheet=3|OwnerPartId=-1|Location.X=1060|Location.Y=400|Color=8388608|FontID=3|IsHidden=T|Text=FERRITE|Name=CATEGORY
|RECORD=41|OwnerIndex=372|IndexInSheet=4|OwnerPartId=-1|Location.X=1058|Location.Y=420|Color=8388608|FontID=3|IsHidden=T|Text=8/6/2013|Name=Date
|RECORD=41|OwnerIndex=372|IndexInSheet=5|OwnerPartId=-1|Location.X=1058|Location.Y=426|Color=8388608|FontID=3|IsHidden=T|Text=125C|Name=MAXTEMP
|RECORD=41|OwnerIndex=372|IndexInSheet=6|OwnerPartId=-1|Location.X=1058|Location.Y=426|Color=8388608|FontID=3|IsHidden=T|Text=-55C|Name=MINTEMP
|RECORD=41|OwnerIndex=372|IndexInSheet=7|OwnerPartId=-1|Location.X=1058|Location.Y=426|Color=8388608|FontID=3|IsHidden=T|Text=100MHZ|Name=P1
|RECORD=41|OwnerIndex=372|IndexInSheet=8|OwnerPartId=-1|Location.X=1058|Location.Y=426|Color=8388608|FontID=3|IsHidden=T|Text=2.2A|Name=P2
|RECORD=41|OwnerIndex=372|IndexInSheet=9|OwnerPartId=-1|Location.X=1058|Location.Y=426|Color=8388608|FontID=3|IsHidden=T|Text=0.05 OHM|Name=P3
|RECORD=41|OwnerIndex=372|IndexInSheet=10|OwnerPartId=-1|Location.X=1058|Location.Y=426|Color=8388608|FontID=3|IsHidden=T|Name=SUB
|RECORD=41|OwnerIndex=372|IndexInSheet=11|OwnerPartId=-1|Location.X=1058|Location.Y=426|Color=8388608|FontID=3|IsHidden=T|Text=0603|Name=SIZE
|RECORD=41|OwnerIndex=372|IndexInSheet=12|OwnerPartId=-1|Location.X=1058|Location.Y=380|Color=8388608|FontID=1|IsHidden=T|Text=*|Name=SHEETPART
|RECORD=41|OwnerIndex=372|IndexInSheet=13|OwnerPartId=-1|Location.X=1058|Location.Y=430|Color=8388608|FontID=1|IsHidden=T|Text=FER, 220 OHM, 100MHZ, 2.2A, 0.05OHM DC, MPZ1608, 0603|Name=DESC
|RECORD=41|OwnerIndex=372|IndexInSheet=14|OwnerPartId=-1|Location.X=1058|Location.Y=426|Color=8388608|FontID=3|IsHidden=T|Text=MPZ1608|Name=OTHER
|RECORD=41|OwnerIndex=372|IndexInSheet=15|OwnerPartId=-1|Location.X=1058|Location.Y=430|Color=8388608|FontID=1|IsHidden=T|Text=<VALENTIUM>|Name=VALENTIUM PART NUM
|RECORD=41|OwnerIndex=372|IndexInSheet=16|OwnerPartId=-1|Location.X=1058|Location.Y=430|Color=8388608|FontID=1|IsHidden=T|Text=Digi-Key|Name=Supplier 1|ReadOnlyState=3
|RECORD=41|OwnerIndex=372|IndexInSheet=17|OwnerPartId=-1|Location.X=1069|Location.Y=378|Color=8388608|FontID=3|Text=220 OHM|Name=VALUE
|RECORD=2|OwnerIndex=372|OwnerPartId=1|FormalType=1|Electrical=4|PinConglomerate=34|PinLength=10|Location.X=1070|Location.Y=400|Name=1|Designator=1|PinPropagationDelay=0.000000E+000
|RECORD=2|OwnerIndex=372|OwnerPartId=1|FormalType=1|Electrical=4|PinConglomerate=32|PinLength=10|Location.X=1110|Location.Y=400|Name=2|Designator=2|PinPropagationDelay=0.000000E+000
|RECORD=12|OwnerIndex=372|IsNotAccesible=T|IndexInSheet=20|OwnerPartId=1|Location.X=1100|Location.Y=400|Radius=5|LineWidth=1|EndAngle=180.000|Color=16711680
|RECORD=12|OwnerIndex=372|IsNotAccesible=T|IndexInSheet=21|OwnerPartId=1|Location.X=1090|Location.Y=400|Radius=5|LineWidth=1|EndAngle=180.000|Color=16711680
|RECORD=12|OwnerIndex=372|IsNotAccesible=T|IndexInSheet=22|OwnerPartId=1|Location.X=1080|Location.Y=400|Radius=5|LineWidth=1|EndAngle=178.662|Color=16711680
|RECORD=13|OwnerIndex=372|IsNotAccesible=T|IndexInSheet=23|OwnerPartId=1|Location.X=1070|Location.Y=400|Corner.X=1075|Corner.Y=400|LineWidth=1|Color=16711680
|RECORD=13|OwnerIndex=372|IsNotAccesible=T|IndexInSheet=24|OwnerPartId=1|Location.X=1105|Location.Y=400|Corner.X=1110|Corner.Y=400|LineWidth=1|Color=16711680
|RECORD=14|OwnerIndex=372|IsNotAccesible=T|IndexInSheet=25|OwnerPartId=1|Location.X=1070|Location.Y=390|Corner.X=1110|Corner.Y=410|LineWidth=1|AreaColor=16777215|IsSolid=T|Transparent=T
|RECORD=41|OwnerIndex=372|IndexInSheet=26|OwnerPartId=-1|Location.X=1069|Location.Y=368|Color=8388608|FontID=1|Text=445-1565-1-ND|Name=Supplier Part Number 1|ReadOnlyState=3
|RECORD=34|OwnerIndex=372|IndexInSheet=-1|OwnerPartId=-1|Location.X=1069|Location.Y=410|Color=8388608|FontID=4|Text=FB2|Name=Designator|ReadOnlyState=1
|RECORD=41|OwnerIndex=372|IndexInSheet=-1|OwnerPartId=-1|Location.X=1071|Location.Y=417|Color=8388608|FontID=3|IsHidden=T|Text=MPZ1608_220OHM_0603|Name=Comment|ReadOnlyState=1
|RECORD=44|OwnerIndex=372
|RECORD=45|OwnerIndex=404|IndexInSheet=-1|Description=Chip Inductor, 2-Leads, Body 1.60x0.80mm, IPC Medium Density|UseComponentLibrary=T|ModelName=INDC1608X09N|ModelType=PCBLIB|DatafileCount=1|ModelDatafileEntity0=INDC1608X09N|ModelDatafileKind0=PCBLib|IsCurrent=T|DatalinksLocked=T|DatabaseDatalinksLocked=T|IntegratedModel=T|DatabaseModel=T
|RECORD=46|OwnerIndex=405
|RECORD=48|OwnerIndex=405
|RECORD=17|IndexInSheet=66|OwnerPartId=-1|ShowNetName=T|Location.X=1300|Location.Y=720|Orientation=1|Color=128|FontID=1|Text=+3.3V_CLEAN
|RECORD=17|IndexInSheet=67|OwnerPartId=-1|Style=4|ShowNetName=T|Location.X=1300|Location.Y=660|Orientation=3|Color=128|FontID=1|Text=GND
|RECORD=22|IndexInSheet=68|OwnerPartId=-1|Location.X=1170|Location.Y=590|Color=255|Orientation=1|Symbol=Thin Cross|IsActive=T|SuppressAll=T
|RECORD=22|IndexInSheet=69|OwnerPartId=-1|Location.X=1170|Location.Y=580|Color=255|Orientation=1|Symbol=Thin Cross|IsActive=T|SuppressAll=T
|RECORD=22|IndexInSheet=70|OwnerPartId=-1|Location.X=1170|Location.Y=570|Color=255|Orientation=1|Symbol=Thin Cross|IsActive=T|SuppressAll=T
|RECORD=17|IndexInSheet=71|OwnerPartId=-1|Style=4|ShowNetName=T|Location.X=1030|Location.Y=550|Orientation=3|Color=128|FontID=1|Text=GND
|RECORD=17|IndexInSheet=72|OwnerPartId=-1|ShowNetName=T|Location.X=960|Location.Y=610|Orientation=2|Color=255|FontID=1|Text=SDA|IsCrossSheetConnector=T
|RECORD=17|IndexInSheet=73|OwnerPartId=-1|ShowNetName=T|Location.X=960|Location.Y=600|Orientation=2|Color=255|FontID=1|Text=SCL|IsCrossSheetConnector=T
|RECORD=17|IndexInSheet=74|OwnerPartId=-1|ShowNetName=T|Location.X=290|Location.Y=880|Orientation=2|Color=255|FontID=1|Text=OE_5356|IsCrossSheetConnector=T
|RECORD=17|IndexInSheet=75|OwnerPartId=-1|ShowNetName=T|Location.X=290|Location.Y=860|Orientation=2|Color=255|FontID=1|Text=SDA|IsCrossSheetConnector=T
|RECORD=17|IndexInSheet=76|OwnerPartId=-1|ShowNetName=T|Location.X=290|Location.Y=850|Orientation=2|Color=255|FontID=1|Text=SCL|IsCrossSheetConnector=T
|RECORD=1|LibReference=RES_0603_10K|ComponentDescription=RES, 10K, 1%, 1/10W, TF, 0603|PartCount=2|DisplayModeCount=1|IndexInSheet=77|OwnerPartId=-1|Location.X=260|Location.Y=830|Orientation=2|CurrentPartId=1|LibraryPath=*|SourceLibraryName=Resistors.IntLib|TargetFileName=*|AreaColor=11599871|Color=128|PartIDLocked=F|DesignItemId=RES_0603_10K|AllPinCount=2
|RECORD=41|OwnerIndex=419|OwnerPartId=-1|Location.X=208|Location.Y=834|Color=8388608|FontID=3|IsHidden=T|Text=7/25/2013|Name=ModifyDate
|RECORD=41|OwnerIndex=419|IndexInSheet=1|OwnerPartId=-1|Location.X=208|Location.Y=834|Color=8388608|FontID=3|IsHidden=T|Text=ERJ-3EKF1002V|Name=MFG PART NUM
|RECORD=41|OwnerIndex=419|IndexInSheet=2|OwnerPartId=-1|Location.X=208|Location.Y=834|Color=8388608|FontID=3|IsHidden=T|Text=PANASONIC|Name=MFG NAME
|RECORD=41|OwnerIndex=419|IndexInSheet=3|OwnerPartId=-1|Location.X=208|Location.Y=834|Color=8388608|FontID=3|IsHidden=T|Text=RES|Name=CATEGORY
|RECORD=41|OwnerIndex=419|IndexInSheet=4|OwnerPartId=-1|Location.X=208|Location.Y=834|Color=8388608|FontID=3|IsHidden=T|Text=7/26/2013|Name=Date
|RECORD=41|OwnerIndex=419|IndexInSheet=5|OwnerPartId=-1|Location.X=208|Location.Y=834|Color=8388608|FontID=3|IsHidden=T|Text=1%|Name=P1
|RECORD=41|OwnerIndex=419|IndexInSheet=6|OwnerPartId=-1|Location.X=208|Location.Y=834|Color=8388608|FontID=3|IsHidden=T|Text=TF|Name=P3
|RECORD=41|OwnerIndex=419|IndexInSheet=7|OwnerPartId=-1|Location.X=208|Location.Y=834|Color=8388608|FontID=3|IsHidden=T|Text=1/10W|Name=P2
|RECORD=41|OwnerIndex=419|IndexInSheet=8|OwnerPartId=-1|Location.X=208|Location.Y=834|Color=8388608|FontID=3|IsHidden=T|Text=125C|Name=MAXTEMP
|RECORD=41|OwnerIndex=419|IndexInSheet=9|OwnerPartId=-1|Location.X=208|Location.Y=834|Color=8388608|FontID=3|IsHidden=T|Text=-55C|Name=MINTEMP
|RECORD=41|OwnerIndex=419|IndexInSheet=10|OwnerPartId=-1|Location.X=208|Location.Y=834|Color=8388608|FontID=3|IsHidden=T|Text=100PPM|Name=OTHER
|RECORD=41|OwnerIndex=419|IndexInSheet=11|OwnerPartId=-1|Location.X=208|Location.Y=834|Color=8388608|FontID=3|IsHidden=T|Text=0603|Name=SIZE
|RECORD=41|OwnerIndex=419|IndexInSheet=12|OwnerPartId=-1|Location.X=208|Location.Y=834|Color=8388608|FontID=3|IsHidden=T|Text=GENERIC|Name=SUB
|RECORD=41|OwnerIndex=419|IndexInSheet=13|OwnerPartId=-1|Location.X=208|Location.Y=834|Color=8388608|FontID=3|IsHidden=T|Text=Digi-Key|Name=Supplier 1|ReadOnlyState=3
|RECORD=41|OwnerIndex=419|IndexInSheet=14|OwnerPartId=-1|Location.X=208|Location.Y=834|Color=8388608|FontID=3|IsHidden=T|Text=P10.0KHCT-ND|Name=Supplier Part Number 1|ReadOnlyState=3
|RECORD=41|OwnerIndex=419|IndexInSheet=15|OwnerPartId=-1|Location.X=208|Location.Y=834|Color=8388608|FontID=1|IsHidden=T|Text=*|Name=SHEETPART
|RECORD=41|OwnerIndex=419|IndexInSheet=16|OwnerPartId=-1|Location.X=208|Location.Y=834|Color=8388608|FontID=1|IsHidden=T|Text=RES, 10K, 1%, 1/10W, TF, 0603|Name=DESC
|RECORD=41|OwnerIndex=419|IndexInSheet=17|OwnerPartId=-1|Location.X=219|Location.Y=814|Color=8388608|FontID=3|Text=10K|Name=VALUE
|RECORD=2|OwnerIndex=419|OwnerPartId=1|FormalType=1|Electrical=4|PinConglomerate=32|PinLength=10|Location.X=250|Location.Y=830|Name=1|Designator=1|PinPropagationDelay=0.000000E+000
|RECORD=2|OwnerIndex=419|OwnerPartId=1|FormalType=1|Electrical=4|PinConglomerate=34|PinLength=10|Location.X=220|Location.Y=830|Name=2|Designator=2|PinPropagationDelay=0.000000E+000
|RECORD=6|OwnerIndex=419|IsNotAccesible=T|IndexInSheet=20|OwnerPartId=1|LineWidth=1|Color=16711680|LocationCount=7|X1=220|Y1=830|X2=223|Y2=827|X3=229|Y3=833|X4=235|Y4=827|X5=241|Y5=833|X6=247|Y6=827|X7=250|Y7=830
|RECORD=41|OwnerIndex=419|IndexInSheet=21|OwnerPartId=-1|Location.X=208|Location.Y=834|Color=8388608|FontID=1|IsHidden=T|Text=<VELENTIUM>|Name=VELENTIUM PART NUM
|RECORD=34|OwnerIndex=419|IndexInSheet=-1|OwnerPartId=-1|Location.X=219|Location.Y=834|Color=8388608|FontID=4|Text=R42|Name=Designator|ReadOnlyState=1
|RECORD=41|OwnerIndex=419|IndexInSheet=-1|OwnerPartId=-1|Location.X=208|Location.Y=834|Color=8388608|FontID=3|IsHidden=T|Text==MFG PART NUM|Name=Comment
|RECORD=44|OwnerIndex=419
|RECORD=45|OwnerIndex=446|IndexInSheet=-1|Description=Chip Resistor, 0603, 2-Leads, Body 1.57x0.85mm, IPC Medium Density|UseComponentLibrary=T|ModelName=RESC1608X50N|ModelType=PCBLIB|DatafileCount=1|ModelDatafileEntity0=RESC1608X50N|ModelDatafileKind0=PCBLib|IsCurrent=T|DatalinksLocked=T|DatabaseDatalinksLocked=T|IntegratedModel=T|DatabaseModel=T
|RECORD=46|OwnerIndex=447
|RECORD=48|OwnerIndex=447
|RECORD=22|IndexInSheet=78|OwnerPartId=-1|Location.X=490|Location.Y=840|Color=255|Orientation=1|Symbol=Thin Cross|IsActive=T|SuppressAll=T
|RECORD=22|IndexInSheet=79|OwnerPartId=-1|Location.X=490|Location.Y=830|Color=255|Orientation=1|Symbol=Thin Cross|IsActive=T|SuppressAll=T
|RECORD=22|IndexInSheet=80|OwnerPartId=-1|Location.X=490|Location.Y=820|Color=255|Orientation=1|Symbol=Thin Cross|IsActive=T|SuppressAll=T
|RECORD=17|IndexInSheet=81|OwnerPartId=-1|ShowNetName=T|Location.X=190|Location.Y=870|Orientation=1|Color=128|FontID=1|Text=+3.3V_CLEAN
|RECORD=17|IndexInSheet=82|OwnerPartId=-1|Style=4|ShowNetName=T|Location.X=360|Location.Y=800|Orientation=3|Color=128|FontID=1|Text=GND
|RECORD=1|LibReference=CAP_0805_22UF_16V|ComponentDescription=CAP, CER, 22.UF, 16V, 20%, X5R, 0805|PartCount=2|DisplayModeCount=1|IndexInSheet=83|OwnerPartId=-1|Location.X=1160|Location.Y=410|Orientation=2|CurrentPartId=1|LibraryPath=*|SourceLibraryName=Capacitors.IntLib|TargetFileName=*|AreaColor=11599871|Color=128|PartIDLocked=F|DesignItemId=CAP_0805_22UF_16V|AllPinCount=2
|RECORD=41|OwnerIndex=455|OwnerPartId=-1|Location.X=1134|Location.Y=392|Color=8388608|FontID=3|IsHidden=T|Text=MURATA|Name=MFG NAME
|RECORD=41|OwnerIndex=455|IndexInSheet=1|OwnerPartId=-1|Location.X=1134|Location.Y=392|Color=8388608|FontID=3|IsHidden=T|Text=GRM219R61C226ME15L|Name=MFG PART NUM
|RECORD=41|OwnerIndex=455|IndexInSheet=2|OwnerPartId=-1|Location.X=1134|Location.Y=392|Color=8388608|FontID=3|IsHidden=T|Text=10/23/2013|Name=MODIFY DATE
|RECORD=41|OwnerIndex=455|IndexInSheet=3|OwnerPartId=-1|Location.X=1134|Location.Y=392|Color=8388608|FontID=3|IsHidden=T|Text=CAP, CER|Name=CATEGORY
|RECORD=41|OwnerIndex=455|IndexInSheet=4|OwnerPartId=-1|Location.X=1134|Location.Y=392|Color=8388608|FontID=3|IsHidden=T|Text=4/11/2006 3:37:28 PM|Name=Date
|RECORD=41|OwnerIndex=455|IndexInSheet=5|OwnerPartId=-1|Location.X=1134|Location.Y=392|Color=8388608|FontID=3|IsHidden=T|Text=*|Name=SHEETPART
|RECORD=41|OwnerIndex=455|IndexInSheet=6|OwnerPartId=-1|Location.X=1134|Location.Y=392|Color=8388608|FontID=3|IsHidden=T|Text=20%|Name=P1
|RECORD=41|OwnerIndex=455|IndexInSheet=7|OwnerPartId=-1|Location.X=1134|Location.Y=392|Color=8388608|FontID=3|IsHidden=T|Text=85C|Name=MAXTEMP
|RECORD=41|OwnerIndex=455|IndexInSheet=8|OwnerPartId=-1|Location.X=1134|Location.Y=392|Color=8388608|FontID=3|IsHidden=T|Text=-55C|Name=MINTEMP
|RECORD=41|OwnerIndex=455|IndexInSheet=9|OwnerPartId=-1|Location.X=1134|Location.Y=392|Color=8388608|FontID=3|IsHidden=T|Name=OTHER
|RECORD=41|OwnerIndex=455|IndexInSheet=10|OwnerPartId=-1|Location.X=1134|Location.Y=392|Color=8388608|FontID=3|IsHidden=T|Text=16V|Name=P2
|RECORD=41|OwnerIndex=455|IndexInSheet=11|OwnerPartId=-1|Location.X=1134|Location.Y=392|Color=8388608|FontID=3|IsHidden=T|Text=X5R|Name=P3
|RECORD=41|OwnerIndex=455|IndexInSheet=12|OwnerPartId=-1|Location.X=1134|Location.Y=392|Color=8388608|FontID=3|IsHidden=T|Text=0805|Name=Size
|RECORD=41|OwnerIndex=455|IndexInSheet=13|OwnerPartId=-1|Location.X=1134|Location.Y=392|Color=8388608|FontID=3|IsHidden=T|Name=SUB
|RECORD=41|OwnerIndex=455|IndexInSheet=14|OwnerPartId=-1|Location.X=1134|Location.Y=392|Color=8388608|FontID=1|IsHidden=T|Text=CAP, CER, 22.UF, 16V, 20%, X5R, 0805|Name=DESC
|RECORD=41|OwnerIndex=455|IndexInSheet=15|OwnerPartId=-1|Location.X=1134|Location.Y=392|Color=8388608|FontID=1|IsHidden=T|Text=Digi-Key|Name=Supplier 1|ReadOnlyState=3
|RECORD=41|OwnerIndex=455|IndexInSheet=16|OwnerPartId=-1|Location.X=1134|Location.Y=392|Color=8388608|FontID=1|IsHidden=T|Text=490-9952-1-ND|Name=Supplier Part Number 1|ReadOnlyState=3
|RECORD=41|OwnerIndex=455|IndexInSheet=17|OwnerPartId=-1|Location.X=1146|Location.Y=355|Color=8388608|FontID=3|Text=22uF|Name=VALUE
|RECORD=2|OwnerIndex=455|OwnerPartId=1|FormalType=1|Electrical=4|PinConglomerate=33|PinLength=10|Location.X=1140|Location.Y=380|Name=2|Designator=2|SwapIdPin=2|SwapIDPart=1|PinPropagationDelay=0.000000E+000
|RECORD=2|OwnerIndex=455|OwnerPartId=1|FormalType=1|Electrical=4|PinConglomerate=35|PinLength=10|Location.X=1140|Location.Y=370|Name=1|Designator=1|SwapIdPin=1|SwapIDPart=1|PinPropagationDelay=0.000000E+000
|RECORD=13|OwnerIndex=455|IsNotAccesible=T|IndexInSheet=20|OwnerPartId=1|Location.X=1140|Location.Y=377|Location.Y_Frac=50000|Corner.X=1140|Corner.Y=380|LineWidth=1|Color=16711680
|RECORD=13|OwnerIndex=455|IsNotAccesible=T|IndexInSheet=21|OwnerPartId=1|Location.X=1140|Location.Y=370|Corner.X=1140|Corner.Y=372|Corner.Y_Frac=50000|LineWidth=1|Color=16711680
|RECORD=13|OwnerIndex=455|IsNotAccesible=T|IndexInSheet=22|OwnerPartId=1|Location.X=1135|Location.Y=377|Location.Y_Frac=50000|Corner.X=1145|Corner.Y=377|Corner.Y_Frac=50000|LineWidth=1|Color=16711680
|RECORD=13|OwnerIndex=455|IsNotAccesible=T|IndexInSheet=23|OwnerPartId=1|Location.X=1135|Location.Y=372|Location.Y_Frac=50000|Corner.X=1145|Corner.Y=372|Corner.Y_Frac=50000|LineWidth=1|Color=16711680
|RECORD=41|OwnerIndex=455|IndexInSheet=24|OwnerPartId=-1|Location.X=1134|Location.Y=392|Color=8388608|FontID=1|IsHidden=T|Text=<VALENTIUM>|Name=VALENTIUM PART NUM
|RECORD=34|OwnerIndex=455|IndexInSheet=-1|OwnerPartId=-1|Location.X=1146|Location.Y=367|Color=8388608|FontID=4|Text=C72|Name=Designator|ReadOnlyState=1
|RECORD=41|OwnerIndex=455|IndexInSheet=-1|OwnerPartId=-1|Location.X=1134|Location.Y=392|Color=8388608|FontID=3|IsHidden=T|Text=CAP_0805_22UF_16V|Name=Comment
|RECORD=44|OwnerIndex=455
|RECORD=45|OwnerIndex=485|IndexInSheet=-1|Description=Chip Capacitor, 0805, 2-Leads, Body 2.00x1.25mm, IPC Medium Density|UseComponentLibrary=T|ModelName=CAPC2012X14N|ModelType=PCBLIB|DatafileCount=1|ModelDatafileEntity0=CAPC2012X14N|ModelDatafileKind0=PCBLib|IsCurrent=T|DatalinksLocked=T|DatabaseDatalinksLocked=T|IntegratedModel=T|DatabaseModel=T
|RECORD=46|OwnerIndex=486
|RECORD=48|OwnerIndex=486
|RECORD=1|LibReference=CAP_0805_22UF_16V|ComponentDescription=CAP, CER, 22.UF, 16V, 20%, X5R, 0805|PartCount=2|DisplayModeCount=1|IndexInSheet=84|OwnerPartId=-1|Location.X=1200|Location.Y=410|Orientation=2|CurrentPartId=1|LibraryPath=*|SourceLibraryName=Capacitors.IntLib|TargetFileName=*|AreaColor=11599871|Color=128|PartIDLocked=F|DesignItemId=CAP_0805_22UF_16V|AllPinCount=2
|RECORD=41|OwnerIndex=489|OwnerPartId=-1|Location.X=1174|Location.Y=392|Color=8388608|FontID=3|IsHidden=T|Text=MURATA|Name=MFG NAME
|RECORD=41|OwnerIndex=489|IndexInSheet=1|OwnerPartId=-1|Location.X=1174|Location.Y=392|Color=8388608|FontID=3|IsHidden=T|Text=GRM219R61C226ME15L|Name=MFG PART NUM
|RECORD=41|OwnerIndex=489|IndexInSheet=2|OwnerPartId=-1|Location.X=1174|Location.Y=392|Color=8388608|FontID=3|IsHidden=T|Text=10/23/2013|Name=MODIFY DATE
|RECORD=41|OwnerIndex=489|IndexInSheet=3|OwnerPartId=-1|Location.X=1174|Location.Y=392|Color=8388608|FontID=3|IsHidden=T|Text=CAP, CER|Name=CATEGORY
|RECORD=41|OwnerIndex=489|IndexInSheet=4|OwnerPartId=-1|Location.X=1174|Location.Y=392|Color=8388608|FontID=3|IsHidden=T|Text=4/11/2006 3:37:28 PM|Name=Date
|RECORD=41|OwnerIndex=489|IndexInSheet=5|OwnerPartId=-1|Location.X=1174|Location.Y=392|Color=8388608|FontID=3|IsHidden=T|Text=*|Name=SHEETPART
|RECORD=41|OwnerIndex=489|IndexInSheet=6|OwnerPartId=-1|Location.X=1174|Location.Y=392|Color=8388608|FontID=3|IsHidden=T|Text=20%|Name=P1
|RECORD=41|OwnerIndex=489|IndexInSheet=7|OwnerPartId=-1|Location.X=1174|Location.Y=392|Color=8388608|FontID=3|IsHidden=T|Text=85C|Name=MAXTEMP
|RECORD=41|OwnerIndex=489|IndexInSheet=8|OwnerPartId=-1|Location.X=1174|Location.Y=392|Color=8388608|FontID=3|IsHidden=T|Text=-55C|Name=MINTEMP
|RECORD=41|OwnerIndex=489|IndexInSheet=9|OwnerPartId=-1|Location.X=1174|Location.Y=392|Color=8388608|FontID=3|IsHidden=T|Name=OTHER
|RECORD=41|OwnerIndex=489|IndexInSheet=10|OwnerPartId=-1|Location.X=1174|Location.Y=392|Color=8388608|FontID=3|IsHidden=T|Text=16V|Name=P2
|RECORD=41|OwnerIndex=489|IndexInSheet=11|OwnerPartId=-1|Location.X=1174|Location.Y=392|Color=8388608|FontID=3|IsHidden=T|Text=X5R|Name=P3
|RECORD=41|OwnerIndex=489|IndexInSheet=12|OwnerPartId=-1|Location.X=1174|Location.Y=392|Color=8388608|FontID=3|IsHidden=T|Text=0805|Name=Size
|RECORD=41|OwnerIndex=489|IndexInSheet=13|OwnerPartId=-1|Location.X=1174|Location.Y=392|Color=8388608|FontID=3|IsHidden=T|Name=SUB
|RECORD=41|OwnerIndex=489|IndexInSheet=14|OwnerPartId=-1|Location.X=1174|Location.Y=392|Color=8388608|FontID=1|IsHidden=T|Text=CAP, CER, 22.UF, 16V, 20%, X5R, 0805|Name=DESC
|RECORD=41|OwnerIndex=489|IndexInSheet=15|OwnerPartId=-1|Location.X=1174|Location.Y=392|Color=8388608|FontID=1|IsHidden=T|Text=Digi-Key|Name=Supplier 1|ReadOnlyState=3
|RECORD=41|OwnerIndex=489|IndexInSheet=16|OwnerPartId=-1|Location.X=1174|Location.Y=392|Color=8388608|FontID=1|IsHidden=T|Text=490-9952-1-ND|Name=Supplier Part Number 1|ReadOnlyState=3
|RECORD=41|OwnerIndex=489|IndexInSheet=17|OwnerPartId=-1|Location.X=1186|Location.Y=355|Color=8388608|FontID=3|Text=22uF|Name=VALUE
|RECORD=2|OwnerIndex=489|OwnerPartId=1|FormalType=1|Electrical=4|PinConglomerate=33|PinLength=10|Location.X=1180|Location.Y=380|Name=2|Designator=2|SwapIdPin=2|SwapIDPart=1|PinPropagationDelay=0.000000E+000
|RECORD=2|OwnerIndex=489|OwnerPartId=1|FormalType=1|Electrical=4|PinConglomerate=35|PinLength=10|Location.X=1180|Location.Y=370|Name=1|Designator=1|SwapIdPin=1|SwapIDPart=1|PinPropagationDelay=0.000000E+000
|RECORD=13|OwnerIndex=489|IsNotAccesible=T|IndexInSheet=20|OwnerPartId=1|Location.X=1180|Location.Y=377|Location.Y_Frac=50000|Corner.X=1180|Corner.Y=380|LineWidth=1|Color=16711680
|RECORD=13|OwnerIndex=489|IsNotAccesible=T|IndexInSheet=21|OwnerPartId=1|Location.X=1180|Location.Y=370|Corner.X=1180|Corner.Y=372|Corner.Y_Frac=50000|LineWidth=1|Color=16711680
|RECORD=13|OwnerIndex=489|IsNotAccesible=T|IndexInSheet=22|OwnerPartId=1|Location.X=1175|Location.Y=377|Location.Y_Frac=50000|Corner.X=1185|Corner.Y=377|Corner.Y_Frac=50000|LineWidth=1|Color=16711680
|RECORD=13|OwnerIndex=489|IsNotAccesible=T|IndexInSheet=23|OwnerPartId=1|Location.X=1175|Location.Y=372|Location.Y_Frac=50000|Corner.X=1185|Corner.Y=372|Corner.Y_Frac=50000|LineWidth=1|Color=16711680
|RECORD=41|OwnerIndex=489|IndexInSheet=24|OwnerPartId=-1|Location.X=1174|Location.Y=392|Color=8388608|FontID=1|IsHidden=T|Text=<VALENTIUM>|Name=VALENTIUM PART NUM
|RECORD=34|OwnerIndex=489|IndexInSheet=-1|OwnerPartId=-1|Location.X=1186|Location.Y=367|Color=8388608|FontID=4|Text=C73|Name=Designator|ReadOnlyState=1
|RECORD=41|OwnerIndex=489|IndexInSheet=-1|OwnerPartId=-1|Location.X=1174|Location.Y=392|Color=8388608|FontID=3|IsHidden=T|Text=CAP_0805_22UF_16V|Name=Comment
|RECORD=44|OwnerIndex=489
|RECORD=45|OwnerIndex=519|IndexInSheet=-1|Description=Chip Capacitor, 0805, 2-Leads, Body 2.00x1.25mm, IPC Medium Density|UseComponentLibrary=T|ModelName=CAPC2012X14N|ModelType=PCBLIB|DatafileCount=1|ModelDatafileEntity0=CAPC2012X14N|ModelDatafileKind0=PCBLib|IsCurrent=T|DatalinksLocked=T|DatabaseDatalinksLocked=T|IntegratedModel=T|DatabaseModel=T
|RECORD=46|OwnerIndex=520
|RECORD=48|OwnerIndex=520
|RECORD=1|LibReference=CAP_0805_22UF_16V|ComponentDescription=CAP, CER, 22.UF, 16V, 20%, X5R, 0805|PartCount=2|DisplayModeCount=1|IndexInSheet=85|OwnerPartId=-1|Location.X=1320|Location.Y=410|Orientation=2|CurrentPartId=1|LibraryPath=*|SourceLibraryName=Capacitors.IntLib|TargetFileName=*|AreaColor=11599871|Color=128|PartIDLocked=F|DesignItemId=CAP_0805_22UF_16V|AllPinCount=2
|RECORD=41|OwnerIndex=523|OwnerPartId=-1|Location.X=1294|Location.Y=392|Color=8388608|FontID=3|IsHidden=T|Text=MURATA|Name=MFG NAME
|RECORD=41|OwnerIndex=523|IndexInSheet=1|OwnerPartId=-1|Location.X=1294|Location.Y=392|Color=8388608|FontID=3|IsHidden=T|Text=GRM219R61C226ME15L|Name=MFG PART NUM
|RECORD=41|OwnerIndex=523|IndexInSheet=2|OwnerPartId=-1|Location.X=1294|Location.Y=392|Color=8388608|FontID=3|IsHidden=T|Text=10/23/2013|Name=MODIFY DATE
|RECORD=41|OwnerIndex=523|IndexInSheet=3|OwnerPartId=-1|Location.X=1294|Location.Y=392|Color=8388608|FontID=3|IsHidden=T|Text=CAP, CER|Name=CATEGORY
|RECORD=41|OwnerIndex=523|IndexInSheet=4|OwnerPartId=-1|Location.X=1294|Location.Y=392|Color=8388608|FontID=3|IsHidden=T|Text=4/11/2006 3:37:28 PM|Name=Date
|RECORD=41|OwnerIndex=523|IndexInSheet=5|OwnerPartId=-1|Location.X=1294|Location.Y=392|Color=8388608|FontID=3|IsHidden=T|Text=*|Name=SHEETPART
|RECORD=41|OwnerIndex=523|IndexInSheet=6|OwnerPartId=-1|Location.X=1294|Location.Y=392|Color=8388608|FontID=3|IsHidden=T|Text=20%|Name=P1
|RECORD=41|OwnerIndex=523|IndexInSheet=7|OwnerPartId=-1|Location.X=1294|Location.Y=392|Color=8388608|FontID=3|IsHidden=T|Text=85C|Name=MAXTEMP
|RECORD=41|OwnerIndex=523|IndexInSheet=8|OwnerPartId=-1|Location.X=1294|Location.Y=392|Color=8388608|FontID=3|IsHidden=T|Text=-55C|Name=MINTEMP
|RECORD=41|OwnerIndex=523|IndexInSheet=9|OwnerPartId=-1|Location.X=1294|Location.Y=392|Color=8388608|FontID=3|IsHidden=T|Name=OTHER
|RECORD=41|OwnerIndex=523|IndexInSheet=10|OwnerPartId=-1|Location.X=1294|Location.Y=392|Color=8388608|FontID=3|IsHidden=T|Text=16V|Name=P2
|RECORD=41|OwnerIndex=523|IndexInSheet=11|OwnerPartId=-1|Location.X=1294|Location.Y=392|Color=8388608|FontID=3|IsHidden=T|Text=X5R|Name=P3
|RECORD=41|OwnerIndex=523|IndexInSheet=12|OwnerPartId=-1|Location.X=1294|Location.Y=392|Color=8388608|FontID=3|IsHidden=T|Text=0805|Name=Size
|RECORD=41|OwnerIndex=523|IndexInSheet=13|OwnerPartId=-1|Location.X=1294|Location.Y=392|Color=8388608|FontID=3|IsHidden=T|Name=SUB
|RECORD=41|OwnerIndex=523|IndexInSheet=14|OwnerPartId=-1|Location.X=1294|Location.Y=392|Color=8388608|FontID=1|IsHidden=T|Text=CAP, CER, 22.UF, 16V, 20%, X5R, 0805|Name=DESC
|RECORD=41|OwnerIndex=523|IndexInSheet=15|OwnerPartId=-1|Location.X=1294|Location.Y=392|Color=8388608|FontID=1|IsHidden=T|Text=Digi-Key|Name=Supplier 1|ReadOnlyState=3
|RECORD=41|OwnerIndex=523|IndexInSheet=16|OwnerPartId=-1|Location.X=1294|Location.Y=392|Color=8388608|FontID=1|IsHidden=T|Text=490-9952-1-ND|Name=Supplier Part Number 1|ReadOnlyState=3
|RECORD=41|OwnerIndex=523|IndexInSheet=17|OwnerPartId=-1|Location.X=1306|Location.Y=355|Color=8388608|FontID=3|Text=22uF|Name=VALUE
|RECORD=2|OwnerIndex=523|OwnerPartId=1|FormalType=1|Electrical=4|PinConglomerate=33|PinLength=10|Location.X=1300|Location.Y=380|Name=2|Designator=2|SwapIdPin=2|SwapIDPart=1|PinPropagationDelay=0.000000E+000
|RECORD=2|OwnerIndex=523|OwnerPartId=1|FormalType=1|Electrical=4|PinConglomerate=35|PinLength=10|Location.X=1300|Location.Y=370|Name=1|Designator=1|SwapIdPin=1|SwapIDPart=1|PinPropagationDelay=0.000000E+000
|RECORD=13|OwnerIndex=523|IsNotAccesible=T|IndexInSheet=20|OwnerPartId=1|Location.X=1300|Location.Y=377|Location.Y_Frac=50000|Corner.X=1300|Corner.Y=380|LineWidth=1|Color=16711680
|RECORD=13|OwnerIndex=523|IsNotAccesible=T|IndexInSheet=21|OwnerPartId=1|Location.X=1300|Location.Y=370|Corner.X=1300|Corner.Y=372|Corner.Y_Frac=50000|LineWidth=1|Color=16711680
|RECORD=13|OwnerIndex=523|IsNotAccesible=T|IndexInSheet=22|OwnerPartId=1|Location.X=1295|Location.Y=377|Location.Y_Frac=50000|Corner.X=1305|Corner.Y=377|Corner.Y_Frac=50000|LineWidth=1|Color=16711680
|RECORD=13|OwnerIndex=523|IsNotAccesible=T|IndexInSheet=23|OwnerPartId=1|Location.X=1295|Location.Y=372|Location.Y_Frac=50000|Corner.X=1305|Corner.Y=372|Corner.Y_Frac=50000|LineWidth=1|Color=16711680
|RECORD=41|OwnerIndex=523|IndexInSheet=24|OwnerPartId=-1|Location.X=1294|Location.Y=392|Color=8388608|FontID=1|IsHidden=T|Text=<VALENTIUM>|Name=VALENTIUM PART NUM
|RECORD=34|OwnerIndex=523|IndexInSheet=-1|OwnerPartId=-1|Location.X=1306|Location.Y=367|Color=8388608|FontID=4|Text=C74|Name=Designator|ReadOnlyState=1
|RECORD=41|OwnerIndex=523|IndexInSheet=-1|OwnerPartId=-1|Location.X=1294|Location.Y=392|Color=8388608|FontID=3|IsHidden=T|Text=CAP_0805_22UF_16V|Name=Comment
|RECORD=44|OwnerIndex=523
|RECORD=45|OwnerIndex=553|IndexInSheet=-1|Description=Chip Capacitor, 0805, 2-Leads, Body 2.00x1.25mm, IPC Medium Density|UseComponentLibrary=T|ModelName=CAPC2012X14N|ModelType=PCBLIB|DatafileCount=1|ModelDatafileEntity0=CAPC2012X14N|ModelDatafileKind0=PCBLib|IsCurrent=T|DatalinksLocked=T|DatabaseDatalinksLocked=T|IntegratedModel=T|DatabaseModel=T
|RECORD=46|OwnerIndex=554
|RECORD=48|OwnerIndex=554
|RECORD=1|LibReference=CAP_0805_22UF_16V|ComponentDescription=CAP, CER, 22.UF, 16V, 20%, X5R, 0805|PartCount=2|DisplayModeCount=1|IndexInSheet=86|OwnerPartId=-1|Location.X=1370|Location.Y=410|Orientation=2|CurrentPartId=1|LibraryPath=*|SourceLibraryName=Capacitors.IntLib|TargetFileName=*|AreaColor=11599871|Color=128|PartIDLocked=F|DesignItemId=CAP_0805_22UF_16V|AllPinCount=2
|RECORD=41|OwnerIndex=557|OwnerPartId=-1|Location.X=1344|Location.Y=392|Color=8388608|FontID=3|IsHidden=T|Text=MURATA|Name=MFG NAME
|RECORD=41|OwnerIndex=557|IndexInSheet=1|OwnerPartId=-1|Location.X=1344|Location.Y=392|Color=8388608|FontID=3|IsHidden=T|Text=GRM219R61C226ME15L|Name=MFG PART NUM
|RECORD=41|OwnerIndex=557|IndexInSheet=2|OwnerPartId=-1|Location.X=1344|Location.Y=392|Color=8388608|FontID=3|IsHidden=T|Text=10/23/2013|Name=MODIFY DATE
|RECORD=41|OwnerIndex=557|IndexInSheet=3|OwnerPartId=-1|Location.X=1344|Location.Y=392|Color=8388608|FontID=3|IsHidden=T|Text=CAP, CER|Name=CATEGORY
|RECORD=41|OwnerIndex=557|IndexInSheet=4|OwnerPartId=-1|Location.X=1344|Location.Y=392|Color=8388608|FontID=3|IsHidden=T|Text=4/11/2006 3:37:28 PM|Name=Date
|RECORD=41|OwnerIndex=557|IndexInSheet=5|OwnerPartId=-1|Location.X=1344|Location.Y=392|Color=8388608|FontID=3|IsHidden=T|Text=*|Name=SHEETPART
|RECORD=41|OwnerIndex=557|IndexInSheet=6|OwnerPartId=-1|Location.X=1344|Location.Y=392|Color=8388608|FontID=3|IsHidden=T|Text=20%|Name=P1
|RECORD=41|OwnerIndex=557|IndexInSheet=7|OwnerPartId=-1|Location.X=1344|Location.Y=392|Color=8388608|FontID=3|IsHidden=T|Text=85C|Name=MAXTEMP
|RECORD=41|OwnerIndex=557|IndexInSheet=8|OwnerPartId=-1|Location.X=1344|Location.Y=392|Color=8388608|FontID=3|IsHidden=T|Text=-55C|Name=MINTEMP
|RECORD=41|OwnerIndex=557|IndexInSheet=9|OwnerPartId=-1|Location.X=1344|Location.Y=392|Color=8388608|FontID=3|IsHidden=T|Name=OTHER
|RECORD=41|OwnerIndex=557|IndexInSheet=10|OwnerPartId=-1|Location.X=1344|Location.Y=392|Color=8388608|FontID=3|IsHidden=T|Text=16V|Name=P2
|RECORD=41|OwnerIndex=557|IndexInSheet=11|OwnerPartId=-1|Location.X=1344|Location.Y=392|Color=8388608|FontID=3|IsHidden=T|Text=X5R|Name=P3
|RECORD=41|OwnerIndex=557|IndexInSheet=12|OwnerPartId=-1|Location.X=1344|Location.Y=392|Color=8388608|FontID=3|IsHidden=T|Text=0805|Name=Size
|RECORD=41|OwnerIndex=557|IndexInSheet=13|OwnerPartId=-1|Location.X=1344|Location.Y=392|Color=8388608|FontID=3|IsHidden=T|Name=SUB
|RECORD=41|OwnerIndex=557|IndexInSheet=14|OwnerPartId=-1|Location.X=1344|Location.Y=392|Color=8388608|FontID=1|IsHidden=T|Text=CAP, CER, 22.UF, 16V, 20%, X5R, 0805|Name=DESC
|RECORD=41|OwnerIndex=557|IndexInSheet=15|OwnerPartId=-1|Location.X=1344|Location.Y=392|Color=8388608|FontID=1|IsHidden=T|Text=Digi-Key|Name=Supplier 1|ReadOnlyState=3
|RECORD=41|OwnerIndex=557|IndexInSheet=16|OwnerPartId=-1|Location.X=1344|Location.Y=392|Color=8388608|FontID=1|IsHidden=T|Text=490-9952-1-ND|Name=Supplier Part Number 1|ReadOnlyState=3
|RECORD=41|OwnerIndex=557|IndexInSheet=17|OwnerPartId=-1|Location.X=1356|Location.Y=355|Color=8388608|FontID=3|Text=22uF|Name=VALUE
|RECORD=2|OwnerIndex=557|OwnerPartId=1|FormalType=1|Electrical=4|PinConglomerate=33|PinLength=10|Location.X=1350|Location.Y=380|Name=2|Designator=2|SwapIdPin=2|SwapIDPart=1|PinPropagationDelay=0.000000E+000
|RECORD=2|OwnerIndex=557|OwnerPartId=1|FormalType=1|Electrical=4|PinConglomerate=35|PinLength=10|Location.X=1350|Location.Y=370|Name=1|Designator=1|SwapIdPin=1|SwapIDPart=1|PinPropagationDelay=0.000000E+000
|RECORD=13|OwnerIndex=557|IsNotAccesible=T|IndexInSheet=20|OwnerPartId=1|Location.X=1350|Location.Y=377|Location.Y_Frac=50000|Corner.X=1350|Corner.Y=380|LineWidth=1|Color=16711680
|RECORD=13|OwnerIndex=557|IsNotAccesible=T|IndexInSheet=21|OwnerPartId=1|Location.X=1350|Location.Y=370|Corner.X=1350|Corner.Y=372|Corner.Y_Frac=50000|LineWidth=1|Color=16711680
|RECORD=13|OwnerIndex=557|IsNotAccesible=T|IndexInSheet=22|OwnerPartId=1|Location.X=1345|Location.Y=377|Location.Y_Frac=50000|Corner.X=1355|Corner.Y=377|Corner.Y_Frac=50000|LineWidth=1|Color=16711680
|RECORD=13|OwnerIndex=557|IsNotAccesible=T|IndexInSheet=23|OwnerPartId=1|Location.X=1345|Location.Y=372|Location.Y_Frac=50000|Corner.X=1355|Corner.Y=372|Corner.Y_Frac=50000|LineWidth=1|Color=16711680
|RECORD=41|OwnerIndex=557|IndexInSheet=24|OwnerPartId=-1|Location.X=1344|Location.Y=392|Color=8388608|FontID=1|IsHidden=T|Text=<VALENTIUM>|Name=VALENTIUM PART NUM
|RECORD=34|OwnerIndex=557|IndexInSheet=-1|OwnerPartId=-1|Location.X=1356|Location.Y=367|Color=8388608|FontID=4|Text=C75|Name=Designator|ReadOnlyState=1
|RECORD=41|OwnerIndex=557|IndexInSheet=-1|OwnerPartId=-1|Location.X=1344|Location.Y=392|Color=8388608|FontID=3|IsHidden=T|Text=CAP_0805_22UF_16V|Name=Comment
|RECORD=44|OwnerIndex=557
|RECORD=45|OwnerIndex=587|IndexInSheet=-1|Description=Chip Capacitor, 0805, 2-Leads, Body 2.00x1.25mm, IPC Medium Density|UseComponentLibrary=T|ModelName=CAPC2012X14N|ModelType=PCBLIB|DatafileCount=1|ModelDatafileEntity0=CAPC2012X14N|ModelDatafileKind0=PCBLib|IsCurrent=T|DatalinksLocked=T|DatabaseDatalinksLocked=T|IntegratedModel=T|DatabaseModel=T
|RECORD=46|OwnerIndex=588
|RECORD=48|OwnerIndex=588
|RECORD=1|LibReference=CAP_0805_1UF_50V|ComponentDescription=CAP, CER, 1.0UF, 50V, 10%, X7R, 0805|PartCount=2|DisplayModeCount=1|IndexInSheet=87|OwnerPartId=-1|Location.X=1380|Location.Y=270|Orientation=2|CurrentPartId=1|LibraryPath=*|SourceLibraryName=Capacitors.IntLib|TargetFileName=*|AreaColor=11599871|Color=128|PartIDLocked=F|DesignItemId=CAP_0805_1UF_50V|AllPinCount=2
|RECORD=41|OwnerIndex=591|OwnerPartId=-1|Location.X=1354|Location.Y=252|Color=8388608|FontID=3|IsHidden=T|Text=MURATA|Name=MFG NAME
|RECORD=41|OwnerIndex=591|IndexInSheet=1|OwnerPartId=-1|Location.X=1354|Location.Y=252|Color=8388608|FontID=3|IsHidden=T|Text=GCM21BR71H105KA03L|Name=MFG PART NUM
|RECORD=41|OwnerIndex=591|IndexInSheet=2|OwnerPartId=-1|Location.X=1354|Location.Y=252|Color=8388608|FontID=3|IsHidden=T|Text=10/23/2013|Name=MODIFY DATE
|RECORD=41|OwnerIndex=591|IndexInSheet=3|OwnerPartId=-1|Location.X=1354|Location.Y=252|Color=8388608|FontID=3|IsHidden=T|Text=CAP, CER|Name=CATEGORY
|RECORD=41|OwnerIndex=591|IndexInSheet=4|OwnerPartId=-1|Location.X=1354|Location.Y=252|Color=8388608|FontID=3|IsHidden=T|Text=10/31/2006 2:46:38 PM|Name=Date
|RECORD=41|OwnerIndex=591|IndexInSheet=5|OwnerPartId=-1|Location.X=1354|Location.Y=252|Color=8388608|FontID=3|IsHidden=T|Text=*|Name=SHEETPART
|RECORD=41|OwnerIndex=591|IndexInSheet=6|OwnerPartId=-1|Location.X=1354|Location.Y=252|Color=8388608|FontID=3|IsHidden=T|Text=10%|Name=P1
|RECORD=41|OwnerIndex=591|IndexInSheet=7|OwnerPartId=-1|Location.X=1354|Location.Y=252|Color=8388608|FontID=3|IsHidden=T|Text=125C|Name=MAXTEMP
|RECORD=41|OwnerIndex=591|IndexInSheet=8|OwnerPartId=-1|Location.X=1354|Location.Y=252|Color=8388608|FontID=3|IsHidden=T|Text=-55C|Name=MINTEMP
|RECORD=41|OwnerIndex=591|IndexInSheet=9|OwnerPartId=-1|Location.X=1354|Location.Y=252|Color=8388608|FontID=3|IsHidden=T|Text=AEC-Q200|Name=OTHER
|RECORD=41|OwnerIndex=591|IndexInSheet=10|OwnerPartId=-1|Location.X=1354|Location.Y=252|Color=8388608|FontID=3|IsHidden=T|Text=50V|Name=P2
|RECORD=41|OwnerIndex=591|IndexInSheet=11|OwnerPartId=-1|Location.X=1354|Location.Y=252|Color=8388608|FontID=3|IsHidden=T|Text=X7R|Name=P3
|RECORD=41|OwnerIndex=591|IndexInSheet=12|OwnerPartId=-1|Location.X=1354|Location.Y=252|Color=8388608|FontID=3|IsHidden=T|Text=0805|Name=Size
|RECORD=41|OwnerIndex=591|IndexInSheet=13|OwnerPartId=-1|Location.X=1354|Location.Y=252|Color=8388608|FontID=3|IsHidden=T|Name=SUB
|RECORD=41|OwnerIndex=591|IndexInSheet=14|OwnerPartId=-1|Location.X=1354|Location.Y=252|Color=8388608|FontID=1|IsHidden=T|Text=CAP, CER, 1.0UF, 50V, 10%, X7R, 0805|Name=DESC
|RECORD=41|OwnerIndex=591|IndexInSheet=15|OwnerPartId=-1|Location.X=1354|Location.Y=252|Color=8388608|FontID=1|IsHidden=T|Text=Digi-Key|Name=Supplier 1|ReadOnlyState=3
|RECORD=41|OwnerIndex=591|IndexInSheet=16|OwnerPartId=-1|Location.X=1354|Location.Y=252|Color=8388608|FontID=1|IsHidden=T|Text=490-10675-1-ND|Name=Supplier Part Number 1|ReadOnlyState=3
|RECORD=41|OwnerIndex=591|IndexInSheet=17|OwnerPartId=-1|Location.X=1366|Location.Y=215|Color=8388608|FontID=3|Text=1.0UF|Name=VALUE
|RECORD=2|OwnerIndex=591|OwnerPartId=1|FormalType=1|Electrical=4|PinConglomerate=33|PinLength=10|Location.X=1360|Location.Y=240|Name=2|Designator=2|SwapIdPin=2|SwapIDPart=1|PinPropagationDelay=0.000000E+000
|RECORD=2|OwnerIndex=591|OwnerPartId=1|FormalType=1|Electrical=4|PinConglomerate=35|PinLength=10|Location.X=1360|Location.Y=230|Name=1|Designator=1|SwapIdPin=1|SwapIDPart=1|PinPropagationDelay=0.000000E+000
|RECORD=13|OwnerIndex=591|IsNotAccesible=T|IndexInSheet=20|OwnerPartId=1|Location.X=1360|Location.Y=237|Location.Y_Frac=50000|Corner.X=1360|Corner.Y=240|LineWidth=1|Color=16711680
|RECORD=13|OwnerIndex=591|IsNotAccesible=T|IndexInSheet=21|OwnerPartId=1|Location.X=1360|Location.Y=230|Corner.X=1360|Corner.Y=232|Corner.Y_Frac=50000|LineWidth=1|Color=16711680
|RECORD=13|OwnerIndex=591|IsNotAccesible=T|IndexInSheet=22|OwnerPartId=1|Location.X=1355|Location.Y=237|Location.Y_Frac=50000|Corner.X=1365|Corner.Y=237|Corner.Y_Frac=50000|LineWidth=1|Color=16711680
|RECORD=13|OwnerIndex=591|IsNotAccesible=T|IndexInSheet=23|OwnerPartId=1|Location.X=1355|Location.Y=232|Location.Y_Frac=50000|Corner.X=1365|Corner.Y=232|Corner.Y_Frac=50000|LineWidth=1|Color=16711680
|RECORD=41|OwnerIndex=591|IndexInSheet=24|OwnerPartId=-1|Location.X=1354|Location.Y=252|Color=8388608|FontID=1|IsHidden=T|Text=<VALENTIUM>|Name=VALENTIUM PART NUM
|RECORD=34|OwnerIndex=591|IndexInSheet=-1|OwnerPartId=-1|Location.X=1366|Location.Y=227|Color=8388608|FontID=4|Text=C84|Name=Designator|ReadOnlyState=1
|RECORD=41|OwnerIndex=591|IndexInSheet=-1|OwnerPartId=-1|Location.X=1354|Location.Y=252|Color=8388608|FontID=3|IsHidden=T|Text=CAP_0805_1UF_50V|Name=Comment
|RECORD=44|OwnerIndex=591
|RECORD=45|OwnerIndex=621|IndexInSheet=-1|Description=Chip Capacitor, 0805, 2-Leads, Body 2.00x1.25mm, IPC Medium Density|UseComponentLibrary=T|ModelName=CAPC2012X14N|ModelType=PCBLIB|DatafileCount=1|ModelDatafileEntity0=CAPC2012X14N|ModelDatafileKind0=PCBLib|IsCurrent=T|DatalinksLocked=T|DatabaseDatalinksLocked=T|IntegratedModel=T|DatabaseModel=T
|RECORD=46|OwnerIndex=622
|RECORD=48|OwnerIndex=622
|RECORD=1|LibReference=CAP_0603_0.01UF_50V|ComponentDescription=CAP, CER, 0.01UF, 50V, 10%, X7R, 0603|PartCount=2|DisplayModeCount=1|IndexInSheet=88|OwnerPartId=-1|Location.X=1060|Location.Y=270|Orientation=2|CurrentPartId=1|LibraryPath=*|SourceLibraryName=Capacitors.IntLib|TargetFileName=*|AreaColor=11599871|Color=128|PartIDLocked=F|DesignItemId=CAP_0603_0.01UF_50V|AllPinCount=2
|RECORD=41|OwnerIndex=625|OwnerPartId=-1|Location.X=1034|Location.Y=252|Color=8388608|FontID=3|IsHidden=T|Text=CAP, CER|Name=CATEGORY
|RECORD=41|OwnerIndex=625|IndexInSheet=1|OwnerPartId=-1|Location.X=1034|Location.Y=252|Color=8388608|FontID=3|IsHidden=T|Text=KEMET|Name=MFG NAME
|RECORD=41|OwnerIndex=625|IndexInSheet=2|OwnerPartId=-1|Location.X=1034|Location.Y=252|Color=8388608|FontID=3|IsHidden=T|Text=C0603C103K5RACTU|Name=MFG PART NUM
|RECORD=41|OwnerIndex=625|IndexInSheet=3|OwnerPartId=-1|Location.X=1034|Location.Y=252|Color=8388608|FontID=3|IsHidden=T|Text=10/23/2013|Name=MODIFY DATE
|RECORD=41|OwnerIndex=625|IndexInSheet=4|OwnerPartId=-1|Location.X=1034|Location.Y=252|Color=8388608|FontID=3|IsHidden=T|Text=7/24/2013|Name=Date
|RECORD=41|OwnerIndex=625|IndexInSheet=5|OwnerPartId=-1|Location.X=1034|Location.Y=252|Color=8388608|FontID=3|IsHidden=T|Text=*|Name=SHEETPART
|RECORD=41|OwnerIndex=625|IndexInSheet=6|OwnerPartId=-1|Location.X=1034|Location.Y=252|Color=8388608|FontID=3|IsHidden=T|Text=10%|Name=P1
|RECORD=41|OwnerIndex=625|IndexInSheet=7|OwnerPartId=-1|Location.X=1034|Location.Y=252|Color=8388608|FontID=3|IsHidden=T|Text=125C|Name=MAXTEMP
|RECORD=41|OwnerIndex=625|IndexInSheet=8|OwnerPartId=-1|Location.X=1034|Location.Y=252|Color=8388608|FontID=3|IsHidden=T|Text=-55C|Name=MINTEMP
|RECORD=41|OwnerIndex=625|IndexInSheet=9|OwnerPartId=-1|Location.X=1034|Location.Y=252|Color=8388608|FontID=3|IsHidden=T|Name=OTHER
|RECORD=41|OwnerIndex=625|IndexInSheet=10|OwnerPartId=-1|Location.X=1034|Location.Y=252|Color=8388608|FontID=3|IsHidden=T|Text=50V|Name=P2
|RECORD=41|OwnerIndex=625|IndexInSheet=11|OwnerPartId=-1|Location.X=1034|Location.Y=252|Color=8388608|FontID=3|IsHidden=T|Text=X7R|Name=P3
|RECORD=41|OwnerIndex=625|IndexInSheet=12|OwnerPartId=-1|Location.X=1034|Location.Y=252|Color=8388608|FontID=3|IsHidden=T|Text=0603|Name=Size
|RECORD=41|OwnerIndex=625|IndexInSheet=13|OwnerPartId=-1|Location.X=1034|Location.Y=252|Color=8388608|FontID=3|IsHidden=T|Name=SUB
|RECORD=41|OwnerIndex=625|IndexInSheet=14|OwnerPartId=-1|Location.X=1034|Location.Y=252|Color=8388608|FontID=3|IsHidden=T|Text=Digi-Key|Name=Supplier 1|ReadOnlyState=3
|RECORD=41|OwnerIndex=625|IndexInSheet=15|OwnerPartId=-1|Location.X=1034|Location.Y=252|Color=8388608|FontID=3|IsHidden=T|Text=399-1091-1-ND|Name=Supplier Part Number 1|ReadOnlyState=3
|RECORD=41|OwnerIndex=625|IndexInSheet=16|OwnerPartId=-1|Location.X=1034|Location.Y=252|Color=8388608|FontID=1|IsHidden=T|Text=CAP, CER, 0.01UF, 50V, 10%, X7R, 0603|Name=DESC
|RECORD=41|OwnerIndex=625|IndexInSheet=17|OwnerPartId=-1|Location.X=1046|Location.Y=215|Color=8388608|FontID=3|Text=0.01uF|Name=VALUE
|RECORD=2|OwnerIndex=625|OwnerPartId=1|FormalType=1|Electrical=4|PinConglomerate=33|PinLength=10|Location.X=1040|Location.Y=240|Name=2|Designator=2|SwapIdPin=2|SwapIDPart=1|PinPropagationDelay=0.000000E+000
|RECORD=2|OwnerIndex=625|OwnerPartId=1|FormalType=1|Electrical=4|PinConglomerate=35|PinLength=10|Location.X=1040|Location.Y=230|Name=1|Designator=1|SwapIdPin=1|SwapIDPart=1|PinPropagationDelay=0.000000E+000
|RECORD=13|OwnerIndex=625|IsNotAccesible=T|IndexInSheet=20|OwnerPartId=1|Location.X=1040|Location.Y=237|Location.Y_Frac=50000|Corner.X=1040|Corner.Y=240|LineWidth=1|Color=16711680
|RECORD=13|OwnerIndex=625|IsNotAccesible=T|IndexInSheet=21|OwnerPartId=1|Location.X=1040|Location.Y=230|Corner.X=1040|Corner.Y=232|Corner.Y_Frac=50000|LineWidth=1|Color=16711680
|RECORD=13|OwnerIndex=625|IsNotAccesible=T|IndexInSheet=22|OwnerPartId=1|Location.X=1035|Location.Y=237|Location.Y_Frac=50000|Corner.X=1045|Corner.Y=237|Corner.Y_Frac=50000|LineWidth=1|Color=16711680
|RECORD=13|OwnerIndex=625|IsNotAccesible=T|IndexInSheet=23|OwnerPartId=1|Location.X=1035|Location.Y=232|Location.Y_Frac=50000|Corner.X=1045|Corner.Y=232|Corner.Y_Frac=50000|LineWidth=1|Color=16711680
|RECORD=41|OwnerIndex=625|IndexInSheet=24|OwnerPartId=-1|Location.X=1034|Location.Y=252|Color=8388608|FontID=1|IsHidden=T|Text=<VALENTIUM>|Name=VALENTIUM PART NUM
|RECORD=34|OwnerIndex=625|IndexInSheet=-1|OwnerPartId=-1|Location.X=1046|Location.Y=227|Color=8388608|FontID=4|Text=C76|Name=Designator|ReadOnlyState=1
|RECORD=41|OwnerIndex=625|IndexInSheet=-1|OwnerPartId=-1|Location.X=1034|Location.Y=252|Color=8388608|FontID=3|IsHidden=T|Text=CAP_0603_0.01UF_50V|Name=Comment|ReadOnlyState=1
|RECORD=44|OwnerIndex=625
|RECORD=45|OwnerIndex=655|IndexInSheet=-1|Description=Chip Capacitor, 0603, 2-Leads, Body 1.60x0.80mm, IPC Medium Density|UseComponentLibrary=T|ModelName=CAPC1608X10N|ModelType=PCBLIB|DatafileCount=1|ModelDatafileEntity0=CAPC1608X10N|ModelDatafileKind0=PCBLib|IsCurrent=T|DatalinksLocked=T|DatabaseDatalinksLocked=T|IntegratedModel=T|DatabaseModel=T
|RECORD=46|OwnerIndex=656
|RECORD=48|OwnerIndex=656
|RECORD=17|IndexInSheet=89|OwnerPartId=-1|Style=4|ShowNetName=T|Location.X=1040|Location.Y=200|Orientation=3|Color=128|FontID=1|Text=GND
|RECORD=17|IndexInSheet=90|OwnerPartId=-1|ShowNetName=T|Location.X=1040|Location.Y=270|Orientation=1|Color=128|FontID=1|Text=+3.3V_CLEAN
|RECORD=17|IndexInSheet=91|OwnerPartId=-1|ShowNetName=T|Location.X=1050|Location.Y=410|Orientation=1|Color=128|FontID=1|Text=+3.3V
|RECORD=17|IndexInSheet=92|OwnerPartId=-1|ShowNetName=T|Location.X=1370|Location.Y=410|Orientation=1|Color=128|FontID=1|Text=+3.3V_CLEAN
|RECORD=17|IndexInSheet=93|OwnerPartId=-1|Style=4|ShowNetName=T|Location.X=1240|Location.Y=340|Orientation=3|Color=128|FontID=1|Text=GND
|RECORD=1|LibReference=SiT5356AI-FQA33-IT-10.000000|ComponentDescription=OSC, 10MHZ, 3.3V, 100PPB, DCTCXO, SMT|PartCount=2|DisplayModeCount=1|IndexInSheet=94|OwnerPartId=-1|Location.X=430|Location.Y=850|CurrentPartId=1|LibraryPath=*|SourceLibraryName=Miscellaneous.IntLib|TargetFileName=*|AreaColor=11599871|Color=128|PartIDLocked=F|DesignItemId=SiT5356AI-FQA33-IT-10.000000|AllPinCount=10
|RECORD=41|OwnerIndex=664|OwnerPartId=-1|Location.X=430|Location.Y=850|Color=8388608|FontID=3|IsHidden=T|Text=SiT5356AI-FQA33-IT-10.000000|Name=MFG PART NUM
|RECORD=41|OwnerIndex=664|IndexInSheet=1|OwnerPartId=-1|Location.X=430|Location.Y=850|Color=8388608|FontID=3|IsHidden=T|Text=9/18/2013|Name=MODIFY DATE
|RECORD=41|OwnerIndex=664|IndexInSheet=2|OwnerPartId=-1|Location.X=430|Location.Y=850|Color=8388608|FontID=3|IsHidden=T|Text=SITIME|Name=MFG NAME
|RECORD=41|OwnerIndex=664|IndexInSheet=3|OwnerPartId=-1|Location.X=430|Location.Y=850|Color=8388608|FontID=3|IsHidden=T|Text=OSC|Name=CATEGORY
|RECORD=41|OwnerIndex=664|IndexInSheet=4|OwnerPartId=-1|Location.X=428|Location.Y=898|Color=8388608|FontID=3|IsHidden=T|Text=9/18/2013|Name=Date
|RECORD=41|OwnerIndex=664|IndexInSheet=5|OwnerPartId=-1|Location.X=428|Location.Y=898|Color=8388608|FontID=3|IsHidden=T|Text=85C|Name=MAXTEMP
|RECORD=41|OwnerIndex=664|IndexInSheet=6|OwnerPartId=-1|Location.X=428|Location.Y=898|Color=8388608|FontID=3|IsHidden=T|Text=-30C|Name=MINTEMP
|RECORD=41|OwnerIndex=664|IndexInSheet=7|OwnerPartId=-1|Location.X=428|Location.Y=898|Color=8388608|FontID=3|IsHidden=T|Name=OTHER
|RECORD=41|OwnerIndex=664|IndexInSheet=8|OwnerPartId=-1|Location.X=428|Location.Y=898|Color=8388608|FontID=3|IsHidden=T|Text=OSC|Name=P1
|RECORD=41|OwnerIndex=664|IndexInSheet=9|OwnerPartId=-1|Location.X=428|Location.Y=898|Color=8388608|FontID=3|IsHidden=T|Text=3.3V|Name=P2
|RECORD=41|OwnerIndex=664|IndexInSheet=10|OwnerPartId=-1|Location.X=428|Location.Y=898|Color=8388608|FontID=3|IsHidden=T|Text=100PPB|Name=P3
|RECORD=41|OwnerIndex=664|IndexInSheet=11|OwnerPartId=-1|Location.X=428|Location.Y=898|Color=8388608|FontID=3|IsHidden=T|Text=5.0X3.2MM|Name=SIZE
|RECORD=41|OwnerIndex=664|IndexInSheet=12|OwnerPartId=-1|Location.X=428|Location.Y=898|Color=8388608|FontID=3|IsHidden=T|Name=SUB
|RECORD=41|OwnerIndex=664|IndexInSheet=13|OwnerPartId=-1|Location.X=428|Location.Y=818|Color=8388608|FontID=1|IsHidden=T|Text=*|Name=SHEETPART
|RECORD=41|OwnerIndex=664|IndexInSheet=14|OwnerPartId=-1|Location.X=418|Location.Y=904|Color=8388608|FontID=1|IsHidden=T|Text=OSC, 10MHZ, 3.3V, 100PPB, DCTCXO, SMT|Name=DESC
|RECORD=41|OwnerIndex=664|IndexInSheet=15|OwnerPartId=-1|Location.X=418|Location.Y=904|Color=8388608|FontID=1|IsHidden=T|Text=<V PART NUM>|Name=VELENTIUM PART NUM
|RECORD=14|OwnerIndex=664|IsNotAccesible=T|IndexInSheet=16|OwnerPartId=1|Location.X=400|Location.Y=800|Corner.X=460|Corner.Y=890|Color=128|AreaColor=11599871|IsSolid=T
|RECORD=2|OwnerIndex=664|OwnerPartId=1|FormalType=1|Electrical=7|PinConglomerate=58|PinLength=30|Location.X=400|Location.Y=850|Name=SCL|Designator=2|PinPropagationDelay=0.000000E+000
|RECORD=2|OwnerIndex=664|OwnerPartId=1|FormalType=1|Electrical=4|PinConglomerate=58|PinLength=30|Location.X=400|Location.Y=880|Name=OE|Designator=1|PinPropagationDelay=0.000000E+000
|RECORD=2|OwnerIndex=664|OwnerPartId=1|FormalType=1|Electrical=4|PinConglomerate=56|PinLength=30|Location.X=460|Location.Y=840|Name=NC|Designator=3|PinPropagationDelay=0.000000E+000
|RECORD=2|OwnerIndex=664|OwnerPartId=1|FormalType=1|Electrical=7|PinConglomerate=58|PinLength=30|Location.X=400|Location.Y=810|Name=GND|Designator=4|PinPropagationDelay=0.000000E+000
|RECORD=41|OwnerIndex=664|IndexInSheet=21|OwnerPartId=-1|Location.X=400|Location.Y=788|Color=8388608|FontID=3|Text=10MHZ|Name=VALUE
|RECORD=2|OwnerIndex=664|OwnerPartId=1|FormalType=1|Electrical=4|PinConglomerate=58|PinLength=30|Location.X=400|Location.Y=830|Name=A0|Designator=5|SwapIDPart=Ž&Ž||PinPropagationDelay=0.000000E+000
|RECORD=2|OwnerIndex=664|OwnerPartId=1|FormalType=1|Electrical=4|PinConglomerate=56|PinLength=30|Location.X=460|Location.Y=860|Name=CLK|Designator=6|SwapIDPart=Ž&Ž||PinPropagationDelay=0.000000E+000
|RECORD=2|OwnerIndex=664|OwnerPartId=1|FormalType=1|Electrical=4|PinConglomerate=56|PinLength=30|Location.X=460|Location.Y=830|Name=NC|Designator=7|SwapIDPart=Ž&Ž||PinPropagationDelay=0.000000E+000
|RECORD=2|OwnerIndex=664|OwnerPartId=1|FormalType=1|Electrical=4|PinConglomerate=56|PinLength=30|Location.X=460|Location.Y=820|Name=NC|Designator=8|SwapIDPart=Ž&Ž||PinPropagationDelay=0.000000E+000
|RECORD=2|OwnerIndex=664|OwnerPartId=1|FormalType=1|Electrical=4|PinConglomerate=56|PinLength=30|Location.X=460|Location.Y=880|Name=VDD|Designator=9|SwapIDPart=Ž&Ž||PinPropagationDelay=0.000000E+000
|RECORD=2|OwnerIndex=664|OwnerPartId=1|FormalType=1|Electrical=4|PinConglomerate=58|PinLength=30|Location.X=400|Location.Y=860|Name=SDA|Designator=10|SwapIDPart=Ž&Ž||PinPropagationDelay=0.000000E+000
|RECORD=34|OwnerIndex=664|IndexInSheet=-1|OwnerPartId=-1|Location.X=400|Location.Y=890|Color=8388608|FontID=4|Text=U13|Name=Designator|ReadOnlyState=1
|RECORD=41|OwnerIndex=664|IndexInSheet=-1|OwnerPartId=-1|Location.X=440|Location.Y=910|Color=8388608|FontID=3|IsHidden=T|Text=SiT5356AI-FQA33-IT-10.000000|Name=Comment
|RECORD=44|OwnerIndex=664
|RECORD=45|OwnerIndex=705|IndexInSheet=-1|UseComponentLibrary=T|ModelName=SIT5155|ModelType=PCBLIB|DatafileCount=1|ModelDatafileEntity0=SIT5155|ModelDatafileKind0=PCBLib|IsCurrent=T|DatalinksLocked=T|DatabaseDatalinksLocked=T|IntegratedModel=T|DatabaseModel=T
|RECORD=46|OwnerIndex=706
|RECORD=48|OwnerIndex=706
|RECORD=1|LibReference=SiT5721AI-KWA33-T-10.000000|ComponentDescription=OSC, 10MHZ, 3.3V, 5PPB, DCOCXO, SMT|PartCount=2|DisplayModeCount=1|IndexInSheet=95|OwnerPartId=-1|Location.X=1110|Location.Y=600|CurrentPartId=1|LibraryPath=*|SourceLibraryName=Miscellaneous.IntLib|TargetFileName=*|AreaColor=11599871|Color=128|PartIDLocked=F|DesignItemId=SiT5721AI-KWA33-T-10.000000|AllPinCount=10
|RECORD=41|OwnerIndex=709|OwnerPartId=-1|Location.X=1110|Location.Y=600|Color=8388608|FontID=3|IsHidden=T|Text=SiT5721AI-KWA33-T-10.000000|Name=MFG PART NUM
|RECORD=41|OwnerIndex=709|IndexInSheet=1|OwnerPartId=-1|Location.X=1110|Location.Y=600|Color=8388608|FontID=3|IsHidden=T|Text=9/18/2013|Name=MODIFY DATE
|RECORD=41|OwnerIndex=709|IndexInSheet=2|OwnerPartId=-1|Location.X=1110|Location.Y=600|Color=8388608|FontID=3|IsHidden=T|Text=SITIME|Name=MFG NAME
|RECORD=41|OwnerIndex=709|IndexInSheet=3|OwnerPartId=-1|Location.X=1110|Location.Y=600|Color=8388608|FontID=3|IsHidden=T|Text=OSC|Name=CATEGORY
|RECORD=41|OwnerIndex=709|IndexInSheet=4|OwnerPartId=-1|Location.X=1108|Location.Y=648|Color=8388608|FontID=3|IsHidden=T|Text=9/18/2013|Name=Date
|RECORD=41|OwnerIndex=709|IndexInSheet=5|OwnerPartId=-1|Location.X=1108|Location.Y=648|Color=8388608|FontID=3|IsHidden=T|Text=85C|Name=MAXTEMP
|RECORD=41|OwnerIndex=709|IndexInSheet=6|OwnerPartId=-1|Location.X=1108|Location.Y=648|Color=8388608|FontID=3|IsHidden=T|Text=-30C|Name=MINTEMP
|RECORD=41|OwnerIndex=709|IndexInSheet=7|OwnerPartId=-1|Location.X=1108|Location.Y=648|Color=8388608|FontID=3|IsHidden=T|Name=OTHER
|RECORD=41|OwnerIndex=709|IndexInSheet=8|OwnerPartId=-1|Location.X=1108|Location.Y=648|Color=8388608|FontID=3|IsHidden=T|Text=OSC|Name=P1
|RECORD=41|OwnerIndex=709|IndexInSheet=9|OwnerPartId=-1|Location.X=1108|Location.Y=648|Color=8388608|FontID=3|IsHidden=T|Text=3.3V|Name=P2
|RECORD=41|OwnerIndex=709|IndexInSheet=10|OwnerPartId=-1|Location.X=1108|Location.Y=648|Color=8388608|FontID=3|IsHidden=T|Text=5PPB|Name=P3
|RECORD=41|OwnerIndex=709|IndexInSheet=11|OwnerPartId=-1|Location.X=1108|Location.Y=648|Color=8388608|FontID=3|IsHidden=T|Text=9.0X7.0MM|Name=SIZE
|RECORD=41|OwnerIndex=709|IndexInSheet=12|OwnerPartId=-1|Location.X=1108|Location.Y=648|Color=8388608|FontID=3|IsHidden=T|Name=SUB
|RECORD=41|OwnerIndex=709|IndexInSheet=13|OwnerPartId=-1|Location.X=1108|Location.Y=568|Color=8388608|FontID=1|IsHidden=T|Text=*|Name=SHEETPART
|RECORD=41|OwnerIndex=709|IndexInSheet=14|OwnerPartId=-1|Location.X=1098|Location.Y=654|Color=8388608|FontID=1|IsHidden=T|Text=OSC, 10MHZ, 3.3V, 5PPB, DCOCXO, SMT|Name=DESC
|RECORD=41|OwnerIndex=709|IndexInSheet=15|OwnerPartId=-1|Location.X=1098|Location.Y=654|Color=8388608|FontID=1|IsHidden=T|Text=<V PART NUM>|Name=VELENTIUM PART NUM
|RECORD=14|OwnerIndex=709|IsNotAccesible=T|IndexInSheet=16|OwnerPartId=1|Location.X=1070|Location.Y=550|Corner.X=1140|Corner.Y=640|Color=128|AreaColor=11599871|IsSolid=T
|RECORD=2|OwnerIndex=709|OwnerPartId=1|FormalType=1|Electrical=7|PinConglomerate=58|PinLength=30|Location.X=1070|Location.Y=600|Name=SCL|Designator=3|PinPropagationDelay=0.000000E+000
|RECORD=2|OwnerIndex=709|OwnerPartId=1|FormalType=1|Electrical=4|PinConglomerate=56|PinLength=30|Location.X=1140|Location.Y=590|Name=NC|Designator=1|PinPropagationDelay=0.000000E+000
|RECORD=2|OwnerIndex=709|OwnerPartId=1|FormalType=1|Electrical=4|PinConglomerate=56|PinLength=30|Location.X=1140|Location.Y=580|Name=NC|Designator=3|PinPropagationDelay=0.000000E+000
|RECORD=2|OwnerIndex=709|OwnerPartId=1|FormalType=1|Electrical=7|PinConglomerate=58|PinLength=30|Location.X=1070|Location.Y=560|Name=GND|Designator=5|PinPropagationDelay=0.000000E+000
|RECORD=41|OwnerIndex=709|IndexInSheet=21|OwnerPartId=-1|Location.X=1070|Location.Y=538|Color=8388608|FontID=3|Text=10MHZ|Name=VALUE
|RECORD=2|OwnerIndex=709|OwnerPartId=1|FormalType=1|Electrical=4|PinConglomerate=56|PinLength=30|Location.X=1140|Location.Y=610|Name=STATUS|Designator=2|SwapIDPart=Ž&Ž||PinPropagationDelay=0.000000E+000
|RECORD=2|OwnerIndex=709|OwnerPartId=1|FormalType=1|Electrical=4|PinConglomerate=56|PinLength=30|Location.X=1140|Location.Y=630|Name=CLK|Designator=6|SwapIDPart=Ž&Ž||PinPropagationDelay=0.000000E+000
|RECORD=2|OwnerIndex=709|OwnerPartId=1|FormalType=1|Electrical=4|PinConglomerate=56|PinLength=30|Location.X=1140|Location.Y=570|Name=NC|Designator=7|SwapIDPart=Ž&Ž||PinPropagationDelay=0.000000E+000
|RECORD=2|OwnerIndex=709|OwnerPartId=1|FormalType=1|Electrical=4|PinConglomerate=56|PinLength=30|Location.X=1140|Location.Y=560|Name=NC|Designator=8|SwapIDPart=Ž&Ž||PinPropagationDelay=0.000000E+000
|RECORD=2|OwnerIndex=709|OwnerPartId=1|FormalType=1|Electrical=4|PinConglomerate=58|PinLength=30|Location.X=1070|Location.Y=630|Name=VDD|Designator=10|SwapIDPart=Ž&Ž||PinPropagationDelay=0.000000E+000
|RECORD=2|OwnerIndex=709|OwnerPartId=1|FormalType=1|Electrical=4|PinConglomerate=58|PinLength=30|Location.X=1070|Location.Y=610|Name=SDA|Designator=4|SwapIDPart=Ž&Ž||PinPropagationDelay=0.000000E+000
|RECORD=34|OwnerIndex=709|IndexInSheet=-1|OwnerPartId=-1|Location.X=1070|Location.Y=640|Color=8388608|FontID=4|Text=U11|Name=Designator|ReadOnlyState=1
|RECORD=41|OwnerIndex=709|IndexInSheet=-1|OwnerPartId=-1|Location.X=1120|Location.Y=660|Color=8388608|FontID=3|IsHidden=T|Text=SiT5721AI-KWA33-T-10.000000|Name=Comment
|RECORD=44|OwnerIndex=709
|RECORD=45|OwnerIndex=750|IndexInSheet=-1|UseComponentLibrary=T|ModelName=SIT5721|ModelType=PCBLIB|DatafileCount=1|ModelDatafileEntity0=SIT5721|ModelDatafileKind0=PCBLib|IsCurrent=T|DatalinksLocked=T|DatabaseDatalinksLocked=T|IntegratedModel=T|DatabaseModel=T
|RECORD=46|OwnerIndex=751
|RECORD=48|OwnerIndex=751
|RECORD=22|IndexInSheet=96|OwnerPartId=-1|Location.X=1170|Location.Y=560|Color=255|Orientation=1|Symbol=Thin Cross|IsActive=T|SuppressAll=T
|RECORD=17|IndexInSheet=97|OwnerPartId=-1|ShowNetName=T|Location.X=1230|Location.Y=610|Color=255|FontID=1|Text=5721_STATUS|IsCrossSheetConnector=T
|RECORD=4|IndexInSheet=98|OwnerPartId=-1|Location.X=1160|Location.Y=990|Color=8388608|FontID=5|Text=RTC
|RECORD=17|IndexInSheet=99|OwnerPartId=-1|Style=4|ShowNetName=T|Location.X=1270|Location.Y=880|Orientation=3|Color=128|FontID=1|Text=GND
|RECORD=17|IndexInSheet=100|OwnerPartId=-1|ShowNetName=T|Location.X=1310|Location.Y=960|Color=255|FontID=1|Text=RTC_MFP|IsCrossSheetConnector=T
|RECORD=17|IndexInSheet=101|OwnerPartId=-1|ShowNetName=T|Location.X=1070|Location.Y=950|Orientation=2|Color=255|FontID=1|Text=SDA|IsCrossSheetConnector=T
|RECORD=17|IndexInSheet=102|OwnerPartId=-1|ShowNetName=T|Location.X=1070|Location.Y=960|Orientation=2|Color=255|FontID=1|Text=SCL|IsCrossSheetConnector=T
|RECORD=1|LibReference=MCSM-090-02984-00X-9|ComponentDescription=Quantum(TM) Miniature Chip Scale Atomic Clock, 3.3 V, 10 MHz, -10 to 70 degC, 9-Pin THD, RoHS, Bulk|PartCount=2|DisplayModeCount=1|IndexInSheet=103|OwnerPartId=-1|Location.X=390|Location.Y=630|CurrentPartId=1|LibraryPath=*|SourceLibraryName=Altium Content Vault|TargetFileName=*|AreaColor=11599871|Color=128|PartIDLocked=T|DesignItemId=CMP-2000-07612-1|AllPinCount=9
|RECORD=14|OwnerIndex=761|IsNotAccesible=T|OwnerPartId=1|Location.X=390|Location.Y=540|Corner.X=490|Corner.Y=630|Color=128|AreaColor=11599871|IsSolid=T
|RECORD=2|OwnerIndex=761|OwnerPartId=1|FormalType=1|Electrical=4|PinConglomerate=58|PinLength=20|Location.X=390|Location.Y=570|Name=TUNE|Designator=1|SwapIDPart=Ž&Ž1|PinPropagationDelay=0.000000E+000
|RECORD=2|OwnerIndex=761|OwnerPartId=1|FormalType=1|Electrical=2|PinConglomerate=56|PinLength=20|Location.X=490|Location.Y=590|Name=1 PPS OUT|Designator=10|SwapIDPart=Ž&Ž1|PinPropagationDelay=0.000000E+000
|RECORD=2|OwnerIndex=761|OwnerPartId=1|FormalType=1|Electrical=2|PinConglomerate=56|PinLength=20|Location.X=490|Location.Y=570|Name=10 MHZ OUT|Designator=12|PinPropagationDelay=0.000000E+000
|RECORD=2|OwnerIndex=761|OwnerPartId=1|FormalType=1|Electrical=4|PinConglomerate=56|PinLength=20|Location.X=490|Location.Y=620|Name=BITE|Designator=4|SwapIDPart=Ž&Ž1|PinPropagationDelay=0.000000E+000
|RECORD=2|OwnerIndex=761|OwnerPartId=1|FormalType=1|Electrical=2|PinConglomerate=58|PinLength=20|Location.X=390|Location.Y=610|Name=TX|Designator=5|SwapIDPart=Ž&Ž1|PinPropagationDelay=0.000000E+000
|RECORD=2|OwnerIndex=761|OwnerPartId=1|FormalType=1|PinConglomerate=58|PinLength=20|Location.X=390|Location.Y=620|Name=RX|Designator=6|SwapIDPart=Ž&Ž1|PinPropagationDelay=0.000000E+000
|RECORD=2|OwnerIndex=761|OwnerPartId=1|FormalType=1|Electrical=7|PinConglomerate=58|PinLength=20|Location.X=390|Location.Y=550|Name=VCC|Designator=7|SwapIDPart=Ž&Ž1|PinPropagationDelay=0.000000E+000
|RECORD=2|OwnerIndex=761|OwnerPartId=1|FormalType=1|Electrical=7|PinConglomerate=56|PinLength=20|Location.X=490|Location.Y=550|Name=GND|Designator=8|SwapIDPart=Ž&Ž1|PinPropagationDelay=0.000000E+000
|RECORD=2|OwnerIndex=761|OwnerPartId=1|FormalType=1|PinConglomerate=58|PinLength=20|Location.X=390|Location.Y=590|Name=1 PPS IN|Designator=9|SwapIDPart=Ž&Ž1|PinPropagationDelay=0.000000E+000
|RECORD=41|OwnerIndex=761|IndexInSheet=10|OwnerPartId=-1|Location.X=368|Location.Y=645|Color=8388608|FontID=1|IsHidden=T|Text=9-Pin Through Hole Device, Body 40.64 x 35.306 mm|Name=Package Description
|RECORD=41|OwnerIndex=761|IndexInSheet=11|OwnerPartId=-1|Location.X=368|Location.Y=645|Color=8388608|FontID=6|IsHidden=T|Text=http://www.microsemi.com/|Name=Manufacturer URL
|RECORD=41|OwnerIndex=761|IndexInSheet=12|OwnerPartId=-1|Location.X=368|Location.Y=645|Color=8388608|FontID=1|IsHidden=T|Text=Microsemi|Name=Manufacturer
|RECORD=41|OwnerIndex=761|IndexInSheet=13|OwnerPartId=-1|Location.X=368|Location.Y=645|Color=8388608|FontID=1|IsHidden=T|Text=03/2017|Name=Datasheet Version
|RECORD=41|OwnerIndex=761|IndexInSheet=14|OwnerPartId=-1|Location.X=368|Location.Y=645|Color=8388608|FontID=1|IsHidden=T|Text=090-02984-00X|Name=Package Reference
|RECORD=41|OwnerIndex=761|IndexInSheet=15|OwnerPartId=-1|Location.X=368|Location.Y=645|Color=8388608|FontID=6|IsHidden=T|Text=https://media.digikey.com/pdf/Data%20Sheets/Microsemi%20PDFs/090-02984-001.pdf|Name=Datasheet URL
|RECORD=41|OwnerIndex=761|IndexInSheet=16|OwnerPartId=-1|Location.X=368|Location.Y=645|Color=8388608|FontID=1|IsHidden=T|Text=ThroughHole|Name=Mounting Technology
|RECORD=34|OwnerIndex=761|IndexInSheet=-1|OwnerPartId=-1|Location.X=390|Location.Y=630|Color=8388608|FontID=1|Text=U10AL|Name=Designator|ReadOnlyState=1
|RECORD=41|OwnerIndex=761|IndexInSheet=-1|OwnerPartId=-1|Location.X=390|Location.Y=530|Color=8388608|FontID=1|Text=SA.45s|Name=Comment
|RECORD=44|OwnerIndex=761
|RECORD=45|OwnerIndex=790|IndexInSheet=-1|Description=THD, 9-Leads, Body 40.64x35.306mm|UseComponentLibrary=T|ModelName=MCSM-090-02984-00X|ModelType=PCBLIB|DatafileCount=1|ModelDatafileEntity0=MCSM-090-02984-00X|ModelDatafileKind0=PCBLib|IsCurrent=T|DatalinksLocked=T|DatabaseDatalinksLocked=T
|RECORD=46|OwnerIndex=791
|RECORD=48|OwnerIndex=791
|RECORD=41|OwnerIndex=793|IndexInSheet=-1|OwnerPartId=-1|Color=8388608|FontID=1|IsHidden=T|Text=2D|Name=Available Preview Images
|RECORD=17|IndexInSheet=104|OwnerPartId=-1|Style=4|ShowNetName=T|Location.X=530|Location.Y=540|Orientation=3|Color=128|FontID=1|Text=GND
|RECORD=17|IndexInSheet=105|OwnerPartId=-1|ShowNetName=T|Location.X=500|Location.Y=920|Orientation=1|Color=128|FontID=1|Text=+3.3V_CLEAN
|RECORD=17|IndexInSheet=106|OwnerPartId=-1|ShowNetName=T|Location.X=300|Location.Y=550|Orientation=1|Color=128|FontID=1|Text=+3.3V_CLEAN
|RECORD=17|IndexInSheet=107|OwnerPartId=-1|ShowNetName=T|Location.X=320|Location.Y=620|Orientation=2|Color=255|FontID=1|Text=MAC_RX|IsCrossSheetConnector=T
|RECORD=17|IndexInSheet=108|OwnerPartId=-1|ShowNetName=T|Location.X=320|Location.Y=610|Orientation=2|Color=255|FontID=1|Text=MAC_TX|IsCrossSheetConnector=T
|RECORD=17|IndexInSheet=109|OwnerPartId=-1|ShowNetName=T|Location.X=320|Location.Y=590|Orientation=2|Color=255|FontID=1|Text=MAC_PPSin|IsCrossSheetConnector=T
|RECORD=17|IndexInSheet=110|OwnerPartId=-1|ShowNetName=T|Location.X=570|Location.Y=620|Color=255|FontID=1|Text=MAC_BITE|IsCrossSheetConnector=T
|RECORD=17|IndexInSheet=111|OwnerPartId=-1|ShowNetName=T|Location.X=570|Location.Y=590|Color=255|FontID=1|Text=MAC_PPSout|IsCrossSheetConnector=T
|RECORD=17|IndexInSheet=112|OwnerPartId=-1|ShowNetName=T|Location.X=570|Location.Y=570|Color=255|FontID=1|Text=MAC_10Mout|IsCrossSheetConnector=T
|RECORD=17|IndexInSheet=113|OwnerPartId=-1|ShowNetName=T|Location.X=260|Location.Y=660|Color=255|FontID=1|Text=GPS1_TP1|IsCrossSheetConnector=T
|RECORD=22|IndexInSheet=114|OwnerPartId=-1|Location.X=370|Location.Y=570|Color=255|Orientation=1|Symbol=Thin Cross|IsActive=T|SuppressAll=T
|RECORD=1|LibReference=MAX-RTC-16-DS3231S-W16#H2|ComponentDescription=Extremely Accurate I2C-Integrated Real-Time Clock/TCXO/Crystal, 16-Pin SO, -40 to 85 degC|PartCount=3|DisplayModeCount=1|IndexInSheet=115|OwnerPartId=-1|Location.X=1140|Location.Y=970|CurrentPartId=1|LibraryPath=*|SourceLibraryName=Altium Content Vault|TargetFileName=*|AreaColor=11599871|Color=128|PartIDLocked=T|DesignItemId=CMP-0254-00293-1|AllPinCount=16
|RECORD=14|OwnerIndex=806|IsNotAccesible=T|OwnerPartId=2|Location.X=1140|Location.Y=920|Corner.X=1190|Corner.Y=970|Color=128|AreaColor=11599871|IsSolid=T
|RECORD=2|OwnerIndex=806|OwnerPartId=2|FormalType=1|Electrical=4|PinConglomerate=58|PinLength=20|Location.X=1140|Location.Y=960|Name=NC|Designator=5|SwapIDPart=Ž&Ž1|PinPropagationDelay=0.000000E+000
|RECORD=2|OwnerIndex=806|OwnerPartId=2|FormalType=1|Electrical=4|PinConglomerate=58|PinLength=20|Location.X=1140|Location.Y=950|Name=NC|Designator=6|SwapIDPart=Ž&Ž1|PinPropagationDelay=0.000000E+000
|RECORD=2|OwnerIndex=806|OwnerPartId=2|FormalType=1|Electrical=4|PinConglomerate=58|PinLength=20|Location.X=1140|Location.Y=940|Name=NC|Designator=7|SwapIDPart=Ž&Ž1|PinPropagationDelay=0.000000E+000
|RECORD=2|OwnerIndex=806|OwnerPartId=2|FormalType=1|Electrical=4|PinConglomerate=58|PinLength=20|Location.X=1140|Location.Y=930|Name=NC|Designator=8|SwapIDPart=Ž&Ž1|PinPropagationDelay=0.000000E+000
|RECORD=2|OwnerIndex=806|OwnerPartId=2|FormalType=1|Electrical=4|PinConglomerate=56|PinLength=20|Location.X=1190|Location.Y=960|Name=NC|Designator=9|SwapIDPart=Ž&Ž1|PinPropagationDelay=0.000000E+000
|RECORD=2|OwnerIndex=806|OwnerPartId=2|FormalType=1|Electrical=4|PinConglomerate=56|PinLength=20|Location.X=1190|Location.Y=950|Name=NC|Designator=10|SwapIDPart=Ž&Ž1|PinPropagationDelay=0.000000E+000
|RECORD=2|OwnerIndex=806|OwnerPartId=2|FormalType=1|Electrical=4|PinConglomerate=56|PinLength=20|Location.X=1190|Location.Y=940|Name=NC|Designator=11|SwapIDPart=Ž&Ž1|PinPropagationDelay=0.000000E+000
|RECORD=2|OwnerIndex=806|OwnerPartId=2|FormalType=1|Electrical=4|PinConglomerate=56|PinLength=20|Location.X=1190|Location.Y=930|Name=NC|Designator=12|SwapIDPart=Ž&Ž1|PinPropagationDelay=0.000000E+000
|RECORD=14|OwnerIndex=806|IsNotAccesible=T|IndexInSheet=9|OwnerPartId=1|Location.X=1140|Location.Y=890|Corner.X=1220|Corner.Y=970|Color=128|AreaColor=11599871|IsSolid=T
|RECORD=2|OwnerIndex=806|OwnerPartId=1|FormalType=1|Electrical=3|PinConglomerate=56|PinLength=20|Location.X=1220|Location.Y=940|Name=32kHz|Designator=1|PinPropagationDelay=0.000000E+000
|RECORD=2|OwnerIndex=806|OwnerPartId=1|FormalType=1|Electrical=7|PinConglomerate=58|PinLength=20|Location.X=1140|Location.Y=900|Name=VCC|Designator=2|PinPropagationDelay=0.000000E+000
|RECORD=2|OwnerIndex=806|OwnerPartId=1|FormalType=1|Electrical=3|PinConglomerate=56|PinLength=20|Location.X=1220|Location.Y=960|Name=I\N\T\/SQW|Designator=3|SwapIDPart=Ž&Ž1|PinPropagationDelay=0.000000E+000
|RECORD=2|OwnerIndex=806|OwnerPartId=1|FormalType=1|Electrical=1|PinConglomerate=56|PinLength=20|Location.X=1220|Location.Y=920|Name=R\S\T\|Designator=4|PinPropagationDelay=0.000000E+000
|RECORD=2|OwnerIndex=806|OwnerPartId=1|FormalType=1|Electrical=7|PinConglomerate=56|PinLength=20|Location.X=1220|Location.Y=900|Name=GND|Designator=13|SwapIDPart=Ž&Ž1|PinPropagationDelay=0.000000E+000
|RECORD=2|OwnerIndex=806|OwnerPartId=1|FormalType=1|Electrical=7|PinConglomerate=58|PinLength=20|Location.X=1140|Location.Y=920|Name=VBAT|Designator=14|SwapIDPart=Ž&Ž1|PinPropagationDelay=0.000000E+000
|RECORD=2|OwnerIndex=806|OwnerPartId=1|FormalType=1|Electrical=1|PinConglomerate=58|PinLength=20|Location.X=1140|Location.Y=950|Name=SDA|Designator=15|SwapIDPart=Ž&Ž1|PinPropagationDelay=0.000000E+000
|RECORD=2|OwnerIndex=806|OwnerPartId=1|SymBol_InnerEdge=3|FormalType=1|PinConglomerate=58|PinLength=20|Location.X=1140|Location.Y=960|Name=SCL|Designator=16|PinPropagationDelay=0.000000E+000
|RECORD=41|OwnerIndex=806|IndexInSheet=18|OwnerPartId=-1|Location.X=1118|Location.Y=985|Color=8388608|FontID=1|IsHidden=T|Text=Manufacturer URL|Name=ComponentLink1Description
|RECORD=41|OwnerIndex=806|IndexInSheet=19|OwnerPartId=-1|Location.X=1118|Location.Y=985|Color=8388608|FontID=6|IsHidden=T|Text=http://pdfserv.maxim-ic.com/package_dwgs/21-0042.PDF|Name=ComponentLink3URL
|RECORD=41|OwnerIndex=806|IndexInSheet=20|OwnerPartId=-1|Location.X=1118|Location.Y=985|Color=8388608|FontID=1|IsHidden=T|Text=Package Specification|Name=ComponentLink3Description
|RECORD=41|OwnerIndex=806|IndexInSheet=21|OwnerPartId=-1|Location.X=1118|Location.Y=985|Color=8388608|FontID=1|IsHidden=T|Text=revD, 2010|Name=PackageVersion
|RECORD=41|OwnerIndex=806|IndexInSheet=22|OwnerPartId=-1|Location.X=1118|Location.Y=985|Color=8388608|FontID=6|IsHidden=T|Text=http://datasheets.maxim-ic.com/en/ds/DS3231.pdf|Name=ComponentLink2URL
|RECORD=41|OwnerIndex=806|IndexInSheet=23|OwnerPartId=-1|Location.X=1118|Location.Y=985|Color=8388608|FontID=1|IsHidden=T|Text=Datasheet|Name=ComponentLink2Description
|RECORD=41|OwnerIndex=806|IndexInSheet=24|OwnerPartId=-1|Location.X=1118|Location.Y=985|Color=8388608|FontID=1|IsHidden=T|Text=W16-H2|Name=PackageReference
|RECORD=41|OwnerIndex=806|IndexInSheet=25|OwnerPartId=-1|Location.X=1118|Location.Y=985|Color=8388608|FontID=1|IsHidden=T|Text=MS-013-AA|Name=Code_JEDEC
|RECORD=41|OwnerIndex=806|IndexInSheet=26|OwnerPartId=-1|Location.X=1118|Location.Y=985|Color=8388608|FontID=6|IsHidden=T|Text=http://www.maxim-ic.com|Name=ComponentLink1URL
|RECORD=41|OwnerIndex=806|IndexInSheet=27|OwnerPartId=-1|Location.X=1118|Location.Y=985|Color=8388608|FontID=1|IsHidden=T|Text=16-Pin Small-Outline IC, Wide (0.3in), 1.27 mm Pitch, SOIC (W)|Name=PackageDescription
|RECORD=41|OwnerIndex=806|IndexInSheet=28|OwnerPartId=-1|Location.X=1118|Location.Y=985|Color=8388608|FontID=1|IsHidden=T|Text=SOIC127P1030-16|Name=Code_IPC
|RECORD=41|OwnerIndex=806|IndexInSheet=29|OwnerPartId=-1|Location.X=1118|Location.Y=985|Color=8388608|FontID=1|IsHidden=T|Text=Rev 8, Jul-2010|Name=DatasheetVersion
|RECORD=34|OwnerIndex=806|IndexInSheet=-1|OwnerPartId=-1|Location.X=1140|Location.Y=970|Color=8388608|FontID=1|Text=U3|Name=Designator|ReadOnlyState=1
|RECORD=41|OwnerIndex=806|IndexInSheet=-1|OwnerPartId=-1|Location.X=1140|Location.Y=880|Color=8388608|FontID=1|Text=DS3231SN|Name=Comment
|RECORD=44|OwnerIndex=806
|RECORD=45|OwnerIndex=855|IndexInSheet=-1|Description=SOIC, 16-Leads, Body 10.3x7.5mm, Pitch 1.27mm, IPC High Density|UseComponentLibrary=T|ModelName=W16-H2_L|ModelType=PCBLIB|DatafileCount=1|ModelDatafileEntity0=W16-H2_L|ModelDatafileKind0=PCBLib|IsCurrent=T|DatalinksLocked=T|DatabaseDatalinksLocked=T
|RECORD=46|OwnerIndex=856
|RECORD=48|OwnerIndex=856
|RECORD=41|OwnerIndex=858|IndexInSheet=-1|OwnerPartId=-1|Color=8388608|FontID=1|IsHidden=T|Text=2D|Name=Available Preview Images
|RECORD=45|OwnerIndex=855|IndexInSheet=-1|Description=SOIC, 16-Leads, Body 10.3x7.5mm, Pitch 1.27mm, IPC Low Density|UseComponentLibrary=T|ModelName=W16-H2_M|ModelType=PCBLIB|DatafileCount=1|ModelDatafileEntity0=W16-H2_M|ModelDatafileKind0=PCBLib|DatalinksLocked=T|DatabaseDatalinksLocked=T
|RECORD=46|OwnerIndex=860
|RECORD=48|OwnerIndex=860
|RECORD=41|OwnerIndex=862|IndexInSheet=-1|OwnerPartId=-1|Color=8388608|FontID=1|IsHidden=T|Text=2D|Name=Available Preview Images
|RECORD=45|OwnerIndex=855|IndexInSheet=-1|Description=SOIC, 16-Leads, Body 10.3x7.5mm, Pitch 1.27mm, IPC Medium Density|UseComponentLibrary=T|ModelName=W16-H2_N|ModelType=PCBLIB|DatafileCount=1|ModelDatafileEntity0=W16-H2_N|ModelDatafileKind0=PCBLib|DatalinksLocked=T|DatabaseDatalinksLocked=T
|RECORD=46|OwnerIndex=864
|RECORD=48|OwnerIndex=864
|RECORD=41|OwnerIndex=866|IndexInSheet=-1|OwnerPartId=-1|Color=8388608|FontID=1|IsHidden=T|Text=2D|Name=Available Preview Images
|RECORD=17|IndexInSheet=116|OwnerPartId=-1|ShowNetName=T|Location.X=1070|Location.Y=900|Orientation=1|Color=128|FontID=1|Text=+3.3V_CLEAN
|RECORD=1|LibReference=60d3b5b901a8747834971d0eb8cf3fd|ComponentDescription=BATTERY HOLDER COIN 20MM SMD|PartCount=2|DisplayModeCount=1|IndexInSheet=117|OwnerPartId=-1|Location.X=980|Location.Y=910|CurrentPartId=1|LibraryPath=*|SourceLibraryName=Altium Content Vault|TargetFileName=*|AreaColor=11599871|Color=128|PartIDLocked=T|DesignItemId=CMP-136216-000002-1|AllPinCount=2
|RECORD=2|OwnerIndex=869|OwnerPartId=1|Electrical=4|PinConglomerate=49|PinLength=20|Location.X=980|Location.Y=890|Name=A|Designator=2|PinPropagationDelay=0.000000E+000
|RECORD=2|OwnerIndex=869|OwnerPartId=1|Electrical=4|PinConglomerate=51|PinLength=20|Location.X=980|Location.Y=870|Name=C|Designator=1|PinPropagationDelay=0.000000E+000
|RECORD=13|OwnerIndex=869|IsNotAccesible=T|IndexInSheet=2|OwnerPartId=1|Location.X=990|Location.Y=890|Corner.X=970|Corner.Y=890|LineWidth=1|Color=16711680
|RECORD=13|OwnerIndex=869|IsNotAccesible=T|IndexInSheet=3|OwnerPartId=1|Location.X=985|Location.Y=884|Corner.X=975|Corner.Y=884|LineWidth=1|Color=16711680
|RECORD=13|OwnerIndex=869|IsNotAccesible=T|IndexInSheet=4|OwnerPartId=1|Location.X=990|Location.Y=877|Corner.X=970|Corner.Y=877|LineWidth=1|Color=16711680
|RECORD=13|OwnerIndex=869|IsNotAccesible=T|IndexInSheet=5|OwnerPartId=1|Location.X=985|Location.Y=870|Corner.X=975|Corner.Y=870|LineWidth=1|Color=16711680
|RECORD=4|OwnerIndex=869|IsNotAccesible=T|IndexInSheet=6|OwnerPartId=1|Location.X=990|Location.Y=898|Orientation=3|Justification=6|Color=8388608|FontID=2|Text=+
|RECORD=4|OwnerIndex=869|IsNotAccesible=T|IndexInSheet=7|OwnerPartId=1|Location.X=995|Location.Y=860|Orientation=2|Justification=6|Color=8388608|FontID=1|Text=-
|RECORD=13|OwnerIndex=869|IsNotAccesible=T|IndexInSheet=8|OwnerPartId=1|Location.X=980|Location.Y=890|Corner.X=980|Corner.Y=893|LineWidth=1|Color=16711680
|RECORD=13|OwnerIndex=869|IsNotAccesible=T|IndexInSheet=9|OwnerPartId=1|Location.X=980|Location.Y=870|Corner.X=980|Corner.Y=867|LineWidth=1|Color=16711680
|RECORD=41|OwnerIndex=869|IndexInSheet=10|OwnerPartId=-1|Location.X=969|Location.Y=912|Color=8388608|FontID=1|IsHidden=T|Text=SMD/SMT|Name=Termination
|RECORD=41|OwnerIndex=869|IndexInSheet=11|OwnerPartId=-1|Location.X=969|Location.Y=912|Color=8388608|FontID=1|IsHidden=T|Text=Surface Mount|Name=Mount
|RECORD=41|OwnerIndex=869|IndexInSheet=12|OwnerPartId=-1|Location.X=969|Location.Y=912|Color=8388608|FontID=1|IsHidden=T|Text=280°C|Name=Max Operating Temperature
|RECORD=41|OwnerIndex=869|IndexInSheet=13|OwnerPartId=-1|Location.X=969|Location.Y=912|Color=8388608|FontID=1|IsHidden=T|Text=-40°C|Name=Min Operating Temperature
|RECORD=41|OwnerIndex=869|IndexInSheet=14|OwnerPartId=-1|Location.X=969|Location.Y=912|Color=8388608|FontID=1|IsHidden=T|Text=400|Name=Package Quantity
|RECORD=41|OwnerIndex=869|IndexInSheet=15|OwnerPartId=-1|Location.X=969|Location.Y=912|Color=8388608|FontID=1|IsHidden=T|Text=1|Name=Number of Cells
|RECORD=41|OwnerIndex=869|IndexInSheet=16|OwnerPartId=-1|Location.X=969|Location.Y=912|Color=8388608|FontID=1|IsHidden=T|Text=SMD/SMT|Name=Case/Package
|RECORD=34|OwnerIndex=869|IndexInSheet=-1|OwnerPartId=-1|Location.X=995|Location.Y=888|Color=8388608|FontID=1|Text=BT1|Name=Designator|ReadOnlyState=1
|RECORD=41|OwnerIndex=869|IndexInSheet=-1|OwnerPartId=1|Location.X=995|Location.Y=878|Color=8388608|FontID=1|Text=BU2032SM-BT-GTR|Name=Comment
|RECORD=44|OwnerIndex=869
|RECORD=45|OwnerIndex=891|IndexInSheet=-1|UseComponentLibrary=T|ModelName=FP-BU2032SM-BT-GTR-MFG|ModelType=PCBLIB|DatafileCount=1|ModelDatafileEntity0=FP-BU2032SM-BT-GTR-MFG|ModelDatafileKind0=PCBLib|IsCurrent=T|DatalinksLocked=T|DatabaseDatalinksLocked=T
|RECORD=46|OwnerIndex=892
|RECORD=48|OwnerIndex=892
|RECORD=17|IndexInSheet=118|OwnerPartId=-1|Style=4|ShowNetName=T|Location.X=980|Location.Y=830|Orientation=3|Color=128|FontID=1|Text=GND
|RECORD=22|IndexInSheet=119|OwnerPartId=-1|Location.X=1240|Location.Y=940|Color=255|Orientation=1|Symbol=Thin Cross|IsActive=T|SuppressAll=T
|RECORD=22|IndexInSheet=120|OwnerPartId=-1|Location.X=1240|Location.Y=920|Color=255|Orientation=1|Symbol=Thin Cross|IsActive=T|SuppressAll=T
|RECORD=1|LibReference=Res3|ComponentDescription=Resistor|PartCount=2|DisplayModeCount=1|IndexInSheet=121|OwnerPartId=-1|Location.X=230|Location.Y=640|Orientation=3|CurrentPartId=1|SourceLibraryName=Miscellaneous Devices.IntLib|TargetFileName=*|AreaColor=11599871|Color=128|PartIDLocked=F|DesignItemId=Res3|AllPinCount=2
|RECORD=2|OwnerIndex=898|OwnerPartId=1|FormalType=1|Electrical=4|PinConglomerate=33|PinLength=10|Location.X=220|Location.Y=640|Name=1|Designator=1|PinPropagationDelay=0.000000E+000
|RECORD=2|OwnerIndex=898|OwnerPartId=1|FormalType=1|Electrical=4|PinConglomerate=35|PinLength=10|Location.X=220|Location.Y=610|Name=2|Designator=2|PinPropagationDelay=0.000000E+000
|RECORD=6|OwnerIndex=898|IsNotAccesible=T|IndexInSheet=2|OwnerPartId=1|LineWidth=1|Color=16711680|LocationCount=7|X1=220|Y1=610|X2=223|Y2=613|X3=217|Y3=619|X4=223|Y4=625|X5=217|Y5=631|X6=223|Y6=637|X7=220|Y7=640
|RECORD=41|OwnerIndex=898|IndexInSheet=3|OwnerPartId=-1|Location.X=216|Location.Y=652|Color=8388608|FontID=1|IsHidden=T|Text=8-Jun-2000|Name=Published
|RECORD=41|OwnerIndex=898|IndexInSheet=4|OwnerPartId=-1|Location.X=216|Location.Y=652|Color=8388608|FontID=1|IsHidden=T|Text=29-May-2009|Name=LatestRevisionDate
|RECORD=41|OwnerIndex=898|IndexInSheet=5|OwnerPartId=-1|Location.X=216|Location.Y=652|Color=8388608|FontID=1|IsHidden=T|Text=IPC-7351 Footprint Added.|Name=LatestRevisionNote
|RECORD=41|OwnerIndex=898|IndexInSheet=6|OwnerPartId=-1|Location.X=216|Location.Y=652|Color=8388608|FontID=1|IsHidden=T|Text=J1-0603|Name=PackageReference
|RECORD=41|OwnerIndex=898|IndexInSheet=7|OwnerPartId=-1|Location.X=216|Location.Y=652|Color=8388608|FontID=1|IsHidden=T|Text=Altium Limited|Name=Publisher
|RECORD=41|OwnerIndex=898|IndexInSheet=8|OwnerPartId=-1|Location.X=216|Location.Y=652|Color=8388608|FontID=1|IsHidden=T|Text=Chip Resistor|Name=PackageDescription
|RECORD=41|OwnerIndex=898|IndexInSheet=9|OwnerPartId=-1|Location.X=224|Location.Y=611|Color=8388608|FontID=1|Text=0 Ohm|Name=Value
|RECORD=34|OwnerIndex=898|IndexInSheet=-1|OwnerPartId=-1|Location.X=224|Location.Y=631|Color=8388608|FontID=1|Text=R17|Name=Designator|ReadOnlyState=1
|RECORD=41|OwnerIndex=898|IndexInSheet=-1|OwnerPartId=-1|Location.X=224|Location.Y=621|Color=8388608|FontID=1|Text=MACPPS|Name=Comment
|RECORD=44|OwnerIndex=898
|RECORD=45|OwnerIndex=913|IndexInSheet=-1|Description=Chip Resistor, Body 1.6x0.8mm, IPC High Density|UseComponentLibrary=T|ModelName=J1-0603|ModelType=PCBLIB|DatafileCount=1|ModelDatafileEntity0=J1-0603|ModelDatafileKind0=PCBLib|IsCurrent=T|DatalinksLocked=T|DatabaseDatalinksLocked=T|IntegratedModel=T|DatabaseModel=T
|RECORD=46|OwnerIndex=914
|RECORD=48|OwnerIndex=914
|RECORD=45|OwnerIndex=913|IndexInSheet=-1|Description=Chip Resistor, Body 3.2x2.5mm, IPC High Density|UseComponentLibrary=T|ModelName=14-1210|ModelType=PCBLIB|DatafileCount=1|ModelDatafileEntity0=14-1210|ModelDatafileKind0=PCBLib|DatalinksLocked=T|DatabaseDatalinksLocked=T|IntegratedModel=T|DatabaseModel=T
|RECORD=46|OwnerIndex=917
|RECORD=48|OwnerIndex=917
|RECORD=45|OwnerIndex=913|IndexInSheet=-1|Description=Chip Resistor, Body 5.0x2.5mm, IPC High Density|UseComponentLibrary=T|ModelName=12Z-2010|ModelType=PCBLIB|DatafileCount=1|ModelDatafileEntity0=12Z-2010|ModelDatafileKind0=PCBLib|DatalinksLocked=T|DatabaseDatalinksLocked=T|IntegratedModel=T|DatabaseModel=T
|RECORD=46|OwnerIndex=920
|RECORD=48|OwnerIndex=920
|RECORD=45|OwnerIndex=913|IndexInSheet=-1|Description=Chip Resistor, Body 6.3x3.2mm, IPC High Density|UseComponentLibrary=T|ModelName=RESC6332|ModelType=PCBLIB|DatafileCount=1|ModelDatafileEntity0=RESC6332|ModelDatafileKind0=PCBLib|DatalinksLocked=T|DatabaseDatalinksLocked=T|IntegratedModel=T|DatabaseModel=T
|RECORD=46|OwnerIndex=923
|RECORD=48|OwnerIndex=923
|RECORD=45|OwnerIndex=913|IndexInSheet=-1|Description=Resistor|UseComponentLibrary=T|ModelName=RESISTOR|ModelType=SIM|IsCurrent=T|DatalinksLocked=T|DatabaseDatalinksLocked=T|IntegratedModel=T|DatabaseModel=T
|RECORD=46|OwnerIndex=926
|RECORD=48|OwnerIndex=926
|RECORD=41|OwnerIndex=928|IndexInSheet=-1|OwnerPartId=-1|Color=8388608|FontID=1|Text=R|Name=Spice Prefix
|RECORD=41|OwnerIndex=928|IndexInSheet=-1|OwnerPartId=-1|Color=8388608|FontID=1|Text=@DESIGNATOR %1 %2 @VALUE|Name=Netlist
|RECORD=41|OwnerIndex=928|IndexInSheet=-1|OwnerPartId=-1|Color=8388608|FontID=1|Text=General|Name=Kind
|RECORD=41|OwnerIndex=928|IndexInSheet=-1|OwnerPartId=-1|Color=8388608|FontID=1|Text=Resistor|Name=SubKind
|RECORD=45|OwnerIndex=913|IndexInSheet=-1|UseComponentLibrary=T|ModelName=Res|ModelType=SI|IsCurrent=T|DatalinksLocked=T|DatabaseDatalinksLocked=T|IntegratedModel=T|DatabaseModel=T
|RECORD=46|OwnerIndex=933
|RECORD=48|OwnerIndex=933
|RECORD=41|OwnerIndex=935|IndexInSheet=-1|OwnerPartId=-1|Color=8388608|FontID=1|Text=Resistor|Name=Type
|RECORD=41|OwnerIndex=935|IndexInSheet=-1|OwnerPartId=-1|Color=8388608|FontID=1|Name=Tech
|RECORD=27|IndexInSheet=122|OwnerPartId=-1|LineWidth=1|Color=8388608|LocationCount=2|X1=1320|Y1=250|X2=1320|Y2=260
|RECORD=27|IndexInSheet=123|OwnerPartId=-1|LineWidth=1|Color=8388608|LocationCount=2|Y1=1100|X2=100|Y2=1100
|RECORD=27|IndexInSheet=124|OwnerPartId=-1|LineWidth=1|Color=8388608|LocationCount=3|X1=210|Y1=830|X2=190|Y2=830|X3=190|Y3=870
|RECORD=27|IndexInSheet=125|OwnerPartId=-1|LineWidth=1|Color=8388608|LocationCount=3|X1=220|Y1=600|X2=340|Y2=600|X3=340|Y3=590
|RECORD=27|IndexInSheet=126|OwnerPartId=-1|LineWidth=1|Color=8388608|LocationCount=3|X1=220|Y1=650|X2=220|Y2=660|X3=260|Y3=660
|RECORD=27|IndexInSheet=127|OwnerPartId=-1|LineWidth=1|Color=8388608|LocationCount=2|X1=370|Y1=830|X2=260|Y2=830
|RECORD=27|IndexInSheet=128|OwnerPartId=-1|LineWidth=1|Color=8388608|LocationCount=2|X1=290|Y1=300|X2=350|Y2=300
|RECORD=27|IndexInSheet=129|OwnerPartId=-1|LineWidth=1|Color=8388608|LocationCount=2|X1=350|Y1=310|X2=290|Y2=310
|RECORD=27|IndexInSheet=130|OwnerPartId=-1|LineWidth=1|Color=8388608|LocationCount=2|X1=290|Y1=320|X2=350|Y2=320
|RECORD=27|IndexInSheet=131|OwnerPartId=-1|LineWidth=1|Color=8388608|LocationCount=2|X1=350|Y1=330|X2=290|Y2=330
|RECORD=27|IndexInSheet=132|OwnerPartId=-1|LineWidth=1|Color=8388608|LocationCount=3|X1=290|Y1=410|X2=310|Y2=410|X3=340|Y3=410
|RECORD=27|IndexInSheet=133|OwnerPartId=-1|LineWidth=1|Color=8388608|LocationCount=2|X1=290|Y1=430|X2=340|Y2=430
|RECORD=27|IndexInSheet=134|OwnerPartId=-1|LineWidth=1|Color=8388608|LocationCount=2|X1=370|Y1=850|X2=290|Y2=850
|RECORD=27|IndexInSheet=135|OwnerPartId=-1|LineWidth=1|Color=8388608|LocationCount=2|X1=370|Y1=860|X2=290|Y2=860
|RECORD=27|IndexInSheet=136|OwnerPartId=-1|LineWidth=1|Color=8388608|LocationCount=2|X1=370|Y1=880|X2=290|Y2=880
|RECORD=27|IndexInSheet=137|OwnerPartId=-1|LineWidth=1|Color=8388608|LocationCount=2|X1=370|Y1=550|X2=300|Y2=550
|RECORD=27|IndexInSheet=138|OwnerPartId=-1|LineWidth=1|Color=8388608|LocationCount=2|X1=340|Y1=400|X2=320|Y2=400
|RECORD=27|IndexInSheet=139|OwnerPartId=-1|LineWidth=1|Color=8388608|LocationCount=4|X1=340|Y1=420|X2=320|Y2=420|X3=320|Y3=400|X4=320|Y4=380
|RECORD=27|IndexInSheet=140|OwnerPartId=-1|LineWidth=1|Color=8388608|LocationCount=3|X1=320|Y1=590|X2=340|Y2=590|X3=370|Y3=590
|RECORD=27|IndexInSheet=141|OwnerPartId=-1|LineWidth=1|Color=8388608|LocationCount=2|X1=320|Y1=610|X2=370|Y2=610
|RECORD=27|IndexInSheet=142|OwnerPartId=-1|LineWidth=1|Color=8388608|LocationCount=2|X1=320|Y1=620|X2=370|Y2=620
|RECORD=27|IndexInSheet=143|OwnerPartId=-1|LineWidth=1|Color=8388608|LocationCount=3|X1=370|Y1=810|X2=360|Y2=810|X3=360|Y3=800
|RECORD=27|IndexInSheet=144|OwnerPartId=-1|LineWidth=1|Color=8388608|LocationCount=2|X1=490|Y1=860|X2=650|Y2=860
|RECORD=27|IndexInSheet=145|OwnerPartId=-1|LineWidth=1|Color=8388608|LocationCount=3|X1=490|Y1=880|X2=500|Y2=880|X3=500|Y3=920
|RECORD=27|IndexInSheet=146|OwnerPartId=-1|LineWidth=1|Color=8388608|LocationCount=3|X1=510|Y1=550|X2=530|Y2=550|X3=530|Y3=540
|RECORD=27|IndexInSheet=147|OwnerPartId=-1|LineWidth=1|Color=8388608|LocationCount=3|X1=510|Y1=570|X2=550|Y2=570|X3=570|Y3=570
|RECORD=27|IndexInSheet=148|OwnerPartId=-1|LineWidth=1|Color=8388608|LocationCount=2|X1=570|Y1=590|X2=510|Y2=590
|RECORD=27|IndexInSheet=149|OwnerPartId=-1|LineWidth=1|Color=8388608|LocationCount=2|X1=510|Y1=620|X2=570|Y2=620
|RECORD=27|IndexInSheet=150|OwnerPartId=-1|LineWidth=1|Color=8388608|LocationCount=2|X1=530|Y1=220|X2=550|Y2=220
|RECORD=27|IndexInSheet=151|OwnerPartId=-1|LineWidth=1|Color=8388608|LocationCount=2|X1=530|Y1=230|X2=550|Y2=230
|RECORD=27|IndexInSheet=152|OwnerPartId=-1|LineWidth=1|Color=8388608|LocationCount=5|X1=530|Y1=240|X2=550|Y2=240|X3=550|Y3=230|X4=550|Y4=220|X5=550|Y5=210
|RECORD=27|IndexInSheet=153|OwnerPartId=-1|LineWidth=1|Color=8388608|LocationCount=2|X1=530|Y1=260|X2=590|Y2=260
|RECORD=27|IndexInSheet=154|OwnerPartId=-1|LineWidth=1|Color=8388608|LocationCount=2|X1=530|Y1=280|X2=590|Y2=280
|RECORD=27|IndexInSheet=155|OwnerPartId=-1|LineWidth=1|Color=8388608|LocationCount=2|X1=590|Y1=290|X2=530|Y2=290
|RECORD=27|IndexInSheet=156|OwnerPartId=-1|LineWidth=1|Color=8388608|LocationCount=2|X1=530|Y1=310|X2=590|Y2=310
|RECORD=27|IndexInSheet=157|OwnerPartId=-1|LineWidth=1|Color=8388608|LocationCount=2|X1=590|Y1=320|X2=530|Y2=320
|RECORD=27|IndexInSheet=158|OwnerPartId=-1|LineWidth=1|Color=8388608|LocationCount=2|X1=530|Y1=330|X2=590|Y2=330
|RECORD=27|IndexInSheet=159|OwnerPartId=-1|LineWidth=1|Color=8388608|LocationCount=2|X1=550|Y1=400|X2=670|Y2=400
|RECORD=27|IndexInSheet=160|OwnerPartId=-1|LineWidth=1|Color=8388608|LocationCount=2|X1=550|Y1=410|X2=590|Y2=410
|RECORD=27|IndexInSheet=161|OwnerPartId=-1|LineWidth=1|Color=8388608|LocationCount=2|X1=550|Y1=420|X2=590|Y2=420
|RECORD=27|IndexInSheet=162|OwnerPartId=-1|LineWidth=1|Color=8388608|LocationCount=2|X1=550|Y1=430|X2=590|Y2=430
|RECORD=27|IndexInSheet=163|OwnerPartId=-1|LineWidth=1|Color=8388608|LocationCount=4|X1=720|Y1=360|X2=720|Y2=350|X3=670|Y3=350|X4=670|Y4=360
|RECORD=27|IndexInSheet=164|OwnerPartId=-1|LineWidth=1|Color=8388608|LocationCount=4|X1=720|Y1=390|X2=720|Y2=400|X3=670|Y3=400|X4=670|Y4=390
|RECORD=27|IndexInSheet=165|OwnerPartId=-1|LineWidth=1|Color=8388608|LocationCount=2|X1=1040|Y1=600|X2=960|Y2=600
|RECORD=27|IndexInSheet=166|OwnerPartId=-1|LineWidth=1|Color=8388608|LocationCount=2|X1=1040|Y1=610|X2=960|Y2=610
|RECORD=27|IndexInSheet=167|OwnerPartId=-1|LineWidth=1|Color=8388608|LocationCount=3|X1=1120|Y1=920|X2=980|Y2=920|X3=980|Y3=910
|RECORD=27|IndexInSheet=168|OwnerPartId=-1|LineWidth=1|Color=8388608|LocationCount=3|X1=1040|Y1=560|X2=1030|Y2=560|X3=1030|Y3=550
|RECORD=27|IndexInSheet=169|OwnerPartId=-1|LineWidth=1|Color=8388608|LocationCount=5|X1=1040|Y1=630|X2=1030|Y2=630|X3=1030|Y3=710|X4=1220|Y4=710|X5=1220|Y5=700
|RECORD=27|IndexInSheet=170|OwnerPartId=-1|LineWidth=1|Color=8388608|LocationCount=7|X1=1040|Y1=210|X2=1080|Y2=210|X3=1120|Y3=210|X4=1160|Y4=210|X5=1200|Y5=210|X6=1240|Y6=210|X7=1280|Y7=210
|RECORD=27|IndexInSheet=171|OwnerPartId=-1|LineWidth=1|Color=8388608|LocationCount=10|X1=1040|Y1=260|X2=1080|Y2=260|X3=1120|Y3=260|X4=1160|Y4=260|X5=1200|Y5=260|X6=1240|Y6=260|X7=1280|Y7=260|X8=1320|Y8=260|X9=1360|Y9=260|X10=1360|Y10=250
|RECORD=27|IndexInSheet=172|OwnerPartId=-1|LineWidth=1|Color=8388608|LocationCount=3|X1=1050|Y1=410|X2=1050|Y2=400|X3=1060|Y3=400
|RECORD=27|IndexInSheet=173|OwnerPartId=-1|LineWidth=1|Color=8388608|LocationCount=2|X1=1120|Y1=900|X2=1070|Y2=900
|RECORD=27|IndexInSheet=174|OwnerPartId=-1|LineWidth=1|Color=8388608|LocationCount=2|X1=1120|Y1=950|X2=1070|Y2=950
|RECORD=27|IndexInSheet=175|OwnerPartId=-1|LineWidth=1|Color=8388608|LocationCount=2|X1=1070|Y1=960|X2=1120|Y2=960
|RECORD=27|IndexInSheet=176|OwnerPartId=-1|LineWidth=1|Color=8388608|LocationCount=4|X1=1120|Y1=400|X2=1140|Y2=400|X3=1180|Y3=400|X4=1210|Y4=400
|RECORD=27|IndexInSheet=177|OwnerPartId=-1|LineWidth=1|Color=8388608|LocationCount=7|X1=1140|Y1=360|X2=1140|Y2=350|X3=1180|Y3=350|X4=1240|Y4=350|X5=1300|Y5=350|X6=1350|Y6=350|X7=1350|Y7=360
|RECORD=27|IndexInSheet=178|OwnerPartId=-1|LineWidth=1|Color=8388608|LocationCount=2|X1=1170|Y1=610|X2=1230|Y2=610
|RECORD=27|IndexInSheet=179|OwnerPartId=-1|LineWidth=1|Color=8388608|LocationCount=2|X1=1170|Y1=630|X2=1330|Y2=630
|RECORD=27|IndexInSheet=180|OwnerPartId=-1|LineWidth=1|Color=8388608|LocationCount=5|X1=1300|Y1=670|X2=1300|Y2=660|X3=1260|Y3=660|X4=1220|Y4=660|X5=1220|Y5=670
|RECORD=27|IndexInSheet=181|OwnerPartId=-1|LineWidth=1|Color=8388608|LocationCount=3|X1=1220|Y1=710|X2=1260|Y2=710|X3=1260|Y3=700
|RECORD=27|IndexInSheet=182|OwnerPartId=-1|LineWidth=1|Color=8388608|LocationCount=3|X1=1240|Y1=900|X2=1270|Y2=900|X3=1270|Y3=880
|RECORD=27|IndexInSheet=183|OwnerPartId=-1|LineWidth=1|Color=8388608|LocationCount=2|X1=1310|Y1=960|X2=1240|Y2=960
|RECORD=27|IndexInSheet=184|OwnerPartId=-1|LineWidth=1|Color=8388608|LocationCount=2|X1=1260|Y1=710|X2=1300|Y2=710
|RECORD=27|IndexInSheet=185|OwnerPartId=-1|LineWidth=1|Color=8388608|LocationCount=5|X1=1270|Y1=400|X2=1300|Y2=400|X3=1350|Y3=400|X4=1370|Y4=400|X5=1370|Y5=410
|RECORD=27|IndexInSheet=186|OwnerPartId=-1|LineWidth=1|Color=8388608|LocationCount=5|X1=1280|Y1=220|X2=1280|Y2=210|X3=1320|Y3=210|X4=1360|Y4=210|X5=1360|Y5=220
|RECORD=27|IndexInSheet=187|OwnerPartId=-1|LineWidth=1|Color=8388608|LocationCount=2|X1=980|Y1=830|X2=980|Y2=850
|RECORD=27|IndexInSheet=188|OwnerPartId=-1|LineWidth=1|Color=8388608|LocationCount=3|X1=1040|Y1=220|X2=1040|Y2=210|X3=1040|Y3=200
|RECORD=27|IndexInSheet=189|OwnerPartId=-1|LineWidth=1|Color=8388608|LocationCount=3|X1=1040|Y1=250|X2=1040|Y2=260|X3=1040|Y3=270
|RECORD=27|IndexInSheet=190|OwnerPartId=-1|LineWidth=1|Color=8388608|LocationCount=2|X1=1080|Y1=220|X2=1080|Y2=210
|RECORD=27|IndexInSheet=191|OwnerPartId=-1|LineWidth=1|Color=8388608|LocationCount=2|X1=1080|Y1=250|X2=1080|Y2=260
|RECORD=27|IndexInSheet=192|OwnerPartId=-1|LineWidth=1|Color=8388608|LocationCount=2|X1=1120|Y1=220|X2=1120|Y2=210
|RECORD=27|IndexInSheet=193|OwnerPartId=-1|LineWidth=1|Color=8388608|LocationCount=2|X1=1120|Y1=250|X2=1120|Y2=260
|RECORD=27|IndexInSheet=194|OwnerPartId=-1|LineWidth=1|Color=8388608|LocationCount=2|X1=1140|Y1=390|X2=1140|Y2=400
|RECORD=27|IndexInSheet=195|OwnerPartId=-1|LineWidth=1|Color=8388608|LocationCount=2|X1=1160|Y1=220|X2=1160|Y2=210
|RECORD=27|IndexInSheet=196|OwnerPartId=-1|LineWidth=1|Color=8388608|LocationCount=2|X1=1160|Y1=250|X2=1160|Y2=260
|RECORD=27|IndexInSheet=197|OwnerPartId=-1|LineWidth=1|Color=8388608|LocationCount=2|X1=1180|Y1=360|X2=1180|Y2=350
|RECORD=27|IndexInSheet=198|OwnerPartId=-1|LineWidth=1|Color=8388608|LocationCount=2|X1=1180|Y1=390|X2=1180|Y2=400
|RECORD=27|IndexInSheet=199|OwnerPartId=-1|LineWidth=1|Color=8388608|LocationCount=2|X1=1200|Y1=220|X2=1200|Y2=210
|RECORD=27|IndexInSheet=200|OwnerPartId=-1|LineWidth=1|Color=8388608|LocationCount=2|X1=1200|Y1=250|X2=1200|Y2=260
|RECORD=27|IndexInSheet=201|OwnerPartId=-1|LineWidth=1|Color=8388608|LocationCount=2|X1=1240|Y1=220|X2=1240|Y2=210
|RECORD=27|IndexInSheet=202|OwnerPartId=-1|LineWidth=1|Color=8388608|LocationCount=2|X1=1240|Y1=250|X2=1240|Y2=260
|RECORD=27|IndexInSheet=203|OwnerPartId=-1|LineWidth=1|Color=8388608|LocationCount=2|X1=1240|Y1=350|X2=1240|Y2=340
|RECORD=27|IndexInSheet=204|OwnerPartId=-1|LineWidth=1|Color=8388608|LocationCount=2|X1=1260|Y1=670|X2=1260|Y2=660
|RECORD=27|IndexInSheet=205|OwnerPartId=-1|LineWidth=1|Color=8388608|LocationCount=2|X1=1280|Y1=250|X2=1280|Y2=260
|RECORD=27|IndexInSheet=206|OwnerPartId=-1|LineWidth=1|Color=8388608|LocationCount=2|X1=1300|Y1=360|X2=1300|Y2=350
|RECORD=27|IndexInSheet=207|OwnerPartId=-1|LineWidth=1|Color=8388608|LocationCount=2|X1=1300|Y1=390|X2=1300|Y2=400
|RECORD=27|IndexInSheet=208|OwnerPartId=-1|LineWidth=1|Color=8388608|LocationCount=3|X1=1300|Y1=700|X2=1300|Y2=710|X3=1300|Y3=720
|RECORD=27|IndexInSheet=209|OwnerPartId=-1|LineWidth=1|Color=8388608|LocationCount=2|X1=1320|Y1=220|X2=1320|Y2=210
|RECORD=27|IndexInSheet=210|OwnerPartId=-1|LineWidth=1|Color=8388608|LocationCount=2|X1=1350|Y1=390|X2=1350|Y2=400
|RECORD=27|IndexInSheet=211|OwnerPartId=-1|LineWidth=1|Color=8388608|LocationCount=4|X1=550|Y1=570|X2=550|Y2=470|X3=310|Y3=470|X4=310|Y4=410
|RECORD=1|LibReference=CAP|ComponentDescription=C0603X104K5RACAUTO|PartCount=2|DisplayModeCount=2|IndexInSheet=212|OwnerPartId=-1|Location.X=1250|Location.Y=680|Orientation=1|CurrentPartId=1|SourceLibraryName=Altium Content Vault|TargetFileName=*|AreaColor=11599871|Color=128|PartIDLocked=F|DesignItemId=CMP-2006-00003-1|AllPinCount=2
|RECORD=2|OwnerIndex=1028|OwnerPartId=1|OwnerPartDisplayMode=1|FormalType=1|Electrical=4|PinConglomerate=35|PinLength=10|Location.X=1260|Location.Y=680|Name=1|Designator=1|PinPropagationDelay=0.000000E+000
|RECORD=2|OwnerIndex=1028|OwnerPartId=1|OwnerPartDisplayMode=1|FormalType=1|Electrical=4|PinConglomerate=33|PinLength=10|Location.X=1260|Location.Y=690|Name=2|Designator=2|PinPropagationDelay=0.000000E+000
|RECORD=13|OwnerIndex=1028|IsNotAccesible=T|IndexInSheet=2|OwnerPartId=1|OwnerPartDisplayMode=1|Location.X=1268|Location.Y=680|Corner.X=1252|Corner.Y=680|LineWidth=1|Color=16711680
|RECORD=13|OwnerIndex=1028|IsNotAccesible=T|IndexInSheet=3|OwnerPartId=1|OwnerPartDisplayMode=1|Location.X=1260|Location.Y=684|Corner.X=1260|Corner.Y=690|LineWidth=1|Color=16711680
|RECORD=12|OwnerIndex=1028|IsNotAccesible=T|IndexInSheet=4|OwnerPartId=1|OwnerPartDisplayMode=1|Location.X=1260|Location.Y=700|Radius=16|LineWidth=1|StartAngle=241.000|EndAngle=270.000|Color=16711680
|RECORD=12|OwnerIndex=1028|IsNotAccesible=T|IndexInSheet=5|OwnerPartId=1|OwnerPartDisplayMode=1|Location.X=1260|Location.Y=700|Radius=16|LineWidth=1|StartAngle=270.000|EndAngle=299.000|Color=16711680
|RECORD=2|OwnerIndex=1028|OwnerPartId=1|FormalType=1|Electrical=4|PinConglomerate=35|PinLength=10|Location.X=1260|Location.Y=680|Name=1|Designator=1|PinPropagationDelay=0.000000E+000
|RECORD=2|OwnerIndex=1028|OwnerPartId=1|FormalType=1|Electrical=4|PinConglomerate=33|PinLength=10|Location.X=1260|Location.Y=690|Name=2|Designator=2|PinPropagationDelay=0.000000E+000
|RECORD=13|OwnerIndex=1028|IsNotAccesible=T|IndexInSheet=8|OwnerPartId=1|Location.X=1252|Location.Y=687|Corner.X=1268|Corner.Y=687|LineWidth=1|Color=16711680
|RECORD=13|OwnerIndex=1028|IsNotAccesible=T|IndexInSheet=9|OwnerPartId=1|Location.X=1268|Location.Y=683|Corner.X=1252|Corner.Y=683|LineWidth=1|Color=16711680
|RECORD=6|OwnerIndex=1028|IsNotAccesible=T|IndexInSheet=10|OwnerPartId=1|LineWidth=1|Color=16711680|LocationCount=2|X1=1260|Y1=680|X2=1260|Y2=683
|RECORD=6|OwnerIndex=1028|IsNotAccesible=T|IndexInSheet=11|OwnerPartId=1|LineWidth=1|Color=16711680|LocationCount=2|X1=1260|Y1=690|X2=1260|Y2=687
|RECORD=41|OwnerIndex=1028|IndexInSheet=12|OwnerPartId=-1|Location.X=1251|Location.Y=702|Color=8388608|FontID=1|IsHidden=T|Text=Kemet|Name=Manufacturer
|RECORD=41|OwnerIndex=1028|IndexInSheet=13|OwnerPartId=-1|Location.X=1251|Location.Y=702|Color=8388608|FontID=1|IsHidden=T|Text=C0603X104K5RACAUTO|Name=Part Number
|RECORD=34|OwnerIndex=1028|IndexInSheet=-1|OwnerPartId=-1|Location.X=1269|Location.Y=681|Color=8388608|FontID=4|Text=C66|Name=Designator|ReadOnlyState=1
|RECORD=41|OwnerIndex=1028|IndexInSheet=-1|OwnerPartId=-1|Location.X=1269|Location.Y=671|Color=8388608|FontID=4|Text=0.1uF|Name=Comment
|RECORD=44|OwnerIndex=1028
|RECORD=45|OwnerIndex=1049|IndexInSheet=-1|Description=Chip Capacitor, 2-Leads, Body 1.60x0.80mm, IPC Low Density|UseComponentLibrary=T|ModelName=CAPC1608X87X45ML20T05|ModelType=PCBLIB|DatafileCount=1|ModelDatafileEntity0=CAPC1608X87X45ML20T05|ModelDatafileKind0=PCBLib|IsCurrent=T|DatalinksLocked=T|DatabaseDatalinksLocked=T
|RECORD=46|OwnerIndex=1050
|RECORD=48|OwnerIndex=1050
|RECORD=41|OwnerIndex=1052|IndexInSheet=-1|OwnerPartId=-1|Color=8388608|FontID=1|Text=2D|Name=Available Preview Images
|RECORD=45|OwnerIndex=1049|IndexInSheet=-1|Description=Chip Capacitor, 2-Leads, Body 1.60x0.80mm, IPC High Density|UseComponentLibrary=T|ModelName=CAPC1608X87X45LL20T05|ModelType=PCBLIB|DatafileCount=1|ModelDatafileEntity0=CAPC1608X87X45LL20T05|ModelDatafileKind0=PCBLib|DatalinksLocked=T|DatabaseDatalinksLocked=T
|RECORD=46|OwnerIndex=1054
|RECORD=48|OwnerIndex=1054
|RECORD=41|OwnerIndex=1056|IndexInSheet=-1|OwnerPartId=-1|Color=8388608|FontID=1|Text=2D|Name=Available Preview Images
|RECORD=45|OwnerIndex=1049|IndexInSheet=-1|Description=Chip Capacitor, 2-Leads, Body 1.60x0.80mm, IPC Medium Density|UseComponentLibrary=T|ModelName=CAPC1608X87X45NL20T05|ModelType=PCBLIB|DatafileCount=1|ModelDatafileEntity0=CAPC1608X87X45NL20T05|ModelDatafileKind0=PCBLib|DatalinksLocked=T|DatabaseDatalinksLocked=T
|RECORD=46|OwnerIndex=1058
|RECORD=48|OwnerIndex=1058
|RECORD=41|OwnerIndex=1060|IndexInSheet=-1|OwnerPartId=-1|Color=8388608|FontID=1|Text=2D|Name=Available Preview Images
|RECORD=1|LibReference=CAP|ComponentDescription=C0603X104K5RACAUTO|PartCount=2|DisplayModeCount=2|IndexInSheet=213|OwnerPartId=-1|Location.X=1070|Location.Y=230|Orientation=1|CurrentPartId=1|SourceLibraryName=Altium Content Vault|TargetFileName=*|AreaColor=11599871|Color=128|PartIDLocked=F|DesignItemId=CMP-2006-00003-1|AllPinCount=2
|RECORD=2|OwnerIndex=1062|OwnerPartId=1|OwnerPartDisplayMode=1|FormalType=1|Electrical=4|PinConglomerate=35|PinLength=10|Location.X=1080|Location.Y=230|Name=1|Designator=1|PinPropagationDelay=0.000000E+000
|RECORD=2|OwnerIndex=1062|OwnerPartId=1|OwnerPartDisplayMode=1|FormalType=1|Electrical=4|PinConglomerate=33|PinLength=10|Location.X=1080|Location.Y=240|Name=2|Designator=2|PinPropagationDelay=0.000000E+000
|RECORD=13|OwnerIndex=1062|IsNotAccesible=T|IndexInSheet=2|OwnerPartId=1|OwnerPartDisplayMode=1|Location.X=1088|Location.Y=230|Corner.X=1072|Corner.Y=230|LineWidth=1|Color=16711680
|RECORD=13|OwnerIndex=1062|IsNotAccesible=T|IndexInSheet=3|OwnerPartId=1|OwnerPartDisplayMode=1|Location.X=1080|Location.Y=234|Corner.X=1080|Corner.Y=240|LineWidth=1|Color=16711680
|RECORD=12|OwnerIndex=1062|IsNotAccesible=T|IndexInSheet=4|OwnerPartId=1|OwnerPartDisplayMode=1|Location.X=1080|Location.Y=250|Radius=16|LineWidth=1|StartAngle=241.000|EndAngle=270.000|Color=16711680
|RECORD=12|OwnerIndex=1062|IsNotAccesible=T|IndexInSheet=5|OwnerPartId=1|OwnerPartDisplayMode=1|Location.X=1080|Location.Y=250|Radius=16|LineWidth=1|StartAngle=270.000|EndAngle=299.000|Color=16711680
|RECORD=2|OwnerIndex=1062|OwnerPartId=1|FormalType=1|Electrical=4|PinConglomerate=35|PinLength=10|Location.X=1080|Location.Y=230|Name=1|Designator=1|PinPropagationDelay=0.000000E+000
|RECORD=2|OwnerIndex=1062|OwnerPartId=1|FormalType=1|Electrical=4|PinConglomerate=33|PinLength=10|Location.X=1080|Location.Y=240|Name=2|Designator=2|PinPropagationDelay=0.000000E+000
|RECORD=13|OwnerIndex=1062|IsNotAccesible=T|IndexInSheet=8|OwnerPartId=1|Location.X=1072|Location.Y=237|Corner.X=1088|Corner.Y=237|LineWidth=1|Color=16711680
|RECORD=13|OwnerIndex=1062|IsNotAccesible=T|IndexInSheet=9|OwnerPartId=1|Location.X=1088|Location.Y=233|Corner.X=1072|Corner.Y=233|LineWidth=1|Color=16711680
|RECORD=6|OwnerIndex=1062|IsNotAccesible=T|IndexInSheet=10|OwnerPartId=1|LineWidth=1|Color=16711680|LocationCount=2|X1=1080|Y1=230|X2=1080|Y2=233
|RECORD=6|OwnerIndex=1062|IsNotAccesible=T|IndexInSheet=11|OwnerPartId=1|LineWidth=1|Color=16711680|LocationCount=2|X1=1080|Y1=240|X2=1080|Y2=237
|RECORD=41|OwnerIndex=1062|IndexInSheet=12|OwnerPartId=-1|Location.X=1071|Location.Y=252|Color=8388608|FontID=1|IsHidden=T|Text=Kemet|Name=Manufacturer
|RECORD=41|OwnerIndex=1062|IndexInSheet=13|OwnerPartId=-1|Location.X=1071|Location.Y=252|Color=8388608|FontID=1|IsHidden=T|Text=C0603X104K5RACAUTO|Name=Part Number
|RECORD=34|OwnerIndex=1062|IndexInSheet=-1|OwnerPartId=-1|Location.X=1089|Location.Y=231|Color=8388608|FontID=4|Text=C77|Name=Designator|ReadOnlyState=1
|RECORD=41|OwnerIndex=1062|IndexInSheet=-1|OwnerPartId=-1|Location.X=1089|Location.Y=221|Color=8388608|FontID=4|Text=0.1uF|Name=Comment
|RECORD=44|OwnerIndex=1062
|RECORD=45|OwnerIndex=1083|IndexInSheet=-1|Description=Chip Capacitor, 2-Leads, Body 1.60x0.80mm, IPC Low Density|UseComponentLibrary=T|ModelName=CAPC1608X87X45ML20T05|ModelType=PCBLIB|DatafileCount=1|ModelDatafileEntity0=CAPC1608X87X45ML20T05|ModelDatafileKind0=PCBLib|IsCurrent=T|DatalinksLocked=T|DatabaseDatalinksLocked=T
|RECORD=46|OwnerIndex=1084
|RECORD=48|OwnerIndex=1084
|RECORD=41|OwnerIndex=1086|IndexInSheet=-1|OwnerPartId=-1|Color=8388608|FontID=1|Text=2D|Name=Available Preview Images
|RECORD=45|OwnerIndex=1083|IndexInSheet=-1|Description=Chip Capacitor, 2-Leads, Body 1.60x0.80mm, IPC High Density|UseComponentLibrary=T|ModelName=CAPC1608X87X45LL20T05|ModelType=PCBLIB|DatafileCount=1|ModelDatafileEntity0=CAPC1608X87X45LL20T05|ModelDatafileKind0=PCBLib|DatalinksLocked=T|DatabaseDatalinksLocked=T
|RECORD=46|OwnerIndex=1088
|RECORD=48|OwnerIndex=1088
|RECORD=41|OwnerIndex=1090|IndexInSheet=-1|OwnerPartId=-1|Color=8388608|FontID=1|Text=2D|Name=Available Preview Images
|RECORD=45|OwnerIndex=1083|IndexInSheet=-1|Description=Chip Capacitor, 2-Leads, Body 1.60x0.80mm, IPC Medium Density|UseComponentLibrary=T|ModelName=CAPC1608X87X45NL20T05|ModelType=PCBLIB|DatafileCount=1|ModelDatafileEntity0=CAPC1608X87X45NL20T05|ModelDatafileKind0=PCBLib|DatalinksLocked=T|DatabaseDatalinksLocked=T
|RECORD=46|OwnerIndex=1092
|RECORD=48|OwnerIndex=1092
|RECORD=41|OwnerIndex=1094|IndexInSheet=-1|OwnerPartId=-1|Color=8388608|FontID=1|Text=2D|Name=Available Preview Images
|RECORD=1|LibReference=CAP|ComponentDescription=C0603X104K5RACAUTO|PartCount=2|DisplayModeCount=2|IndexInSheet=214|OwnerPartId=-1|Location.X=1110|Location.Y=230|Orientation=1|CurrentPartId=1|SourceLibraryName=Altium Content Vault|TargetFileName=*|AreaColor=11599871|Color=128|PartIDLocked=F|DesignItemId=CMP-2006-00003-1|AllPinCount=2
|RECORD=2|OwnerIndex=1096|OwnerPartId=1|OwnerPartDisplayMode=1|FormalType=1|Electrical=4|PinConglomerate=35|PinLength=10|Location.X=1120|Location.Y=230|Name=1|Designator=1|PinPropagationDelay=0.000000E+000
|RECORD=2|OwnerIndex=1096|OwnerPartId=1|OwnerPartDisplayMode=1|FormalType=1|Electrical=4|PinConglomerate=33|PinLength=10|Location.X=1120|Location.Y=240|Name=2|Designator=2|PinPropagationDelay=0.000000E+000
|RECORD=13|OwnerIndex=1096|IsNotAccesible=T|IndexInSheet=2|OwnerPartId=1|OwnerPartDisplayMode=1|Location.X=1128|Location.Y=230|Corner.X=1112|Corner.Y=230|LineWidth=1|Color=16711680
|RECORD=13|OwnerIndex=1096|IsNotAccesible=T|IndexInSheet=3|OwnerPartId=1|OwnerPartDisplayMode=1|Location.X=1120|Location.Y=234|Corner.X=1120|Corner.Y=240|LineWidth=1|Color=16711680
|RECORD=12|OwnerIndex=1096|IsNotAccesible=T|IndexInSheet=4|OwnerPartId=1|OwnerPartDisplayMode=1|Location.X=1120|Location.Y=250|Radius=16|LineWidth=1|StartAngle=241.000|EndAngle=270.000|Color=16711680
|RECORD=12|OwnerIndex=1096|IsNotAccesible=T|IndexInSheet=5|OwnerPartId=1|OwnerPartDisplayMode=1|Location.X=1120|Location.Y=250|Radius=16|LineWidth=1|StartAngle=270.000|EndAngle=299.000|Color=16711680
|RECORD=2|OwnerIndex=1096|OwnerPartId=1|FormalType=1|Electrical=4|PinConglomerate=35|PinLength=10|Location.X=1120|Location.Y=230|Name=1|Designator=1|PinPropagationDelay=0.000000E+000
|RECORD=2|OwnerIndex=1096|OwnerPartId=1|FormalType=1|Electrical=4|PinConglomerate=33|PinLength=10|Location.X=1120|Location.Y=240|Name=2|Designator=2|PinPropagationDelay=0.000000E+000
|RECORD=13|OwnerIndex=1096|IsNotAccesible=T|IndexInSheet=8|OwnerPartId=1|Location.X=1112|Location.Y=237|Corner.X=1128|Corner.Y=237|LineWidth=1|Color=16711680
|RECORD=13|OwnerIndex=1096|IsNotAccesible=T|IndexInSheet=9|OwnerPartId=1|Location.X=1128|Location.Y=233|Corner.X=1112|Corner.Y=233|LineWidth=1|Color=16711680
|RECORD=6|OwnerIndex=1096|IsNotAccesible=T|IndexInSheet=10|OwnerPartId=1|LineWidth=1|Color=16711680|LocationCount=2|X1=1120|Y1=230|X2=1120|Y2=233
|RECORD=6|OwnerIndex=1096|IsNotAccesible=T|IndexInSheet=11|OwnerPartId=1|LineWidth=1|Color=16711680|LocationCount=2|X1=1120|Y1=240|X2=1120|Y2=237
|RECORD=41|OwnerIndex=1096|IndexInSheet=12|OwnerPartId=-1|Location.X=1111|Location.Y=252|Color=8388608|FontID=1|IsHidden=T|Text=Kemet|Name=Manufacturer
|RECORD=41|OwnerIndex=1096|IndexInSheet=13|OwnerPartId=-1|Location.X=1111|Location.Y=252|Color=8388608|FontID=1|IsHidden=T|Text=C0603X104K5RACAUTO|Name=Part Number
|RECORD=34|OwnerIndex=1096|IndexInSheet=-1|OwnerPartId=-1|Location.X=1129|Location.Y=231|Color=8388608|FontID=4|Text=C78|Name=Designator|ReadOnlyState=1
|RECORD=41|OwnerIndex=1096|IndexInSheet=-1|OwnerPartId=-1|Location.X=1129|Location.Y=221|Color=8388608|FontID=4|Text=0.1uF|Name=Comment
|RECORD=44|OwnerIndex=1096
|RECORD=45|OwnerIndex=1117|IndexInSheet=-1|Description=Chip Capacitor, 2-Leads, Body 1.60x0.80mm, IPC Low Density|UseComponentLibrary=T|ModelName=CAPC1608X87X45ML20T05|ModelType=PCBLIB|DatafileCount=1|ModelDatafileEntity0=CAPC1608X87X45ML20T05|ModelDatafileKind0=PCBLib|IsCurrent=T|DatalinksLocked=T|DatabaseDatalinksLocked=T
|RECORD=46|OwnerIndex=1118
|RECORD=48|OwnerIndex=1118
|RECORD=41|OwnerIndex=1120|IndexInSheet=-1|OwnerPartId=-1|Color=8388608|FontID=1|Text=2D|Name=Available Preview Images
|RECORD=45|OwnerIndex=1117|IndexInSheet=-1|Description=Chip Capacitor, 2-Leads, Body 1.60x0.80mm, IPC High Density|UseComponentLibrary=T|ModelName=CAPC1608X87X45LL20T05|ModelType=PCBLIB|DatafileCount=1|ModelDatafileEntity0=CAPC1608X87X45LL20T05|ModelDatafileKind0=PCBLib|DatalinksLocked=T|DatabaseDatalinksLocked=T
|RECORD=46|OwnerIndex=1122
|RECORD=48|OwnerIndex=1122
|RECORD=41|OwnerIndex=1124|IndexInSheet=-1|OwnerPartId=-1|Color=8388608|FontID=1|Text=2D|Name=Available Preview Images
|RECORD=45|OwnerIndex=1117|IndexInSheet=-1|Description=Chip Capacitor, 2-Leads, Body 1.60x0.80mm, IPC Medium Density|UseComponentLibrary=T|ModelName=CAPC1608X87X45NL20T05|ModelType=PCBLIB|DatafileCount=1|ModelDatafileEntity0=CAPC1608X87X45NL20T05|ModelDatafileKind0=PCBLib|DatalinksLocked=T|DatabaseDatalinksLocked=T
|RECORD=46|OwnerIndex=1126
|RECORD=48|OwnerIndex=1126
|RECORD=41|OwnerIndex=1128|IndexInSheet=-1|OwnerPartId=-1|Color=8388608|FontID=1|Text=2D|Name=Available Preview Images
|RECORD=1|LibReference=CAP|ComponentDescription=C0603X104K5RACAUTO|PartCount=2|DisplayModeCount=2|IndexInSheet=215|OwnerPartId=-1|Location.X=1150|Location.Y=230|Orientation=1|CurrentPartId=1|SourceLibraryName=Altium Content Vault|TargetFileName=*|AreaColor=11599871|Color=128|PartIDLocked=F|DesignItemId=CMP-2006-00003-1|AllPinCount=2
|RECORD=2|OwnerIndex=1130|OwnerPartId=1|OwnerPartDisplayMode=1|FormalType=1|Electrical=4|PinConglomerate=35|PinLength=10|Location.X=1160|Location.Y=230|Name=1|Designator=1|PinPropagationDelay=0.000000E+000
|RECORD=2|OwnerIndex=1130|OwnerPartId=1|OwnerPartDisplayMode=1|FormalType=1|Electrical=4|PinConglomerate=33|PinLength=10|Location.X=1160|Location.Y=240|Name=2|Designator=2|PinPropagationDelay=0.000000E+000
|RECORD=13|OwnerIndex=1130|IsNotAccesible=T|IndexInSheet=2|OwnerPartId=1|OwnerPartDisplayMode=1|Location.X=1168|Location.Y=230|Corner.X=1152|Corner.Y=230|LineWidth=1|Color=16711680
|RECORD=13|OwnerIndex=1130|IsNotAccesible=T|IndexInSheet=3|OwnerPartId=1|OwnerPartDisplayMode=1|Location.X=1160|Location.Y=234|Corner.X=1160|Corner.Y=240|LineWidth=1|Color=16711680
|RECORD=12|OwnerIndex=1130|IsNotAccesible=T|IndexInSheet=4|OwnerPartId=1|OwnerPartDisplayMode=1|Location.X=1160|Location.Y=250|Radius=16|LineWidth=1|StartAngle=241.000|EndAngle=270.000|Color=16711680
|RECORD=12|OwnerIndex=1130|IsNotAccesible=T|IndexInSheet=5|OwnerPartId=1|OwnerPartDisplayMode=1|Location.X=1160|Location.Y=250|Radius=16|LineWidth=1|StartAngle=270.000|EndAngle=299.000|Color=16711680
|RECORD=2|OwnerIndex=1130|OwnerPartId=1|FormalType=1|Electrical=4|PinConglomerate=35|PinLength=10|Location.X=1160|Location.Y=230|Name=1|Designator=1|PinPropagationDelay=0.000000E+000
|RECORD=2|OwnerIndex=1130|OwnerPartId=1|FormalType=1|Electrical=4|PinConglomerate=33|PinLength=10|Location.X=1160|Location.Y=240|Name=2|Designator=2|PinPropagationDelay=0.000000E+000
|RECORD=13|OwnerIndex=1130|IsNotAccesible=T|IndexInSheet=8|OwnerPartId=1|Location.X=1152|Location.Y=237|Corner.X=1168|Corner.Y=237|LineWidth=1|Color=16711680
|RECORD=13|OwnerIndex=1130|IsNotAccesible=T|IndexInSheet=9|OwnerPartId=1|Location.X=1168|Location.Y=233|Corner.X=1152|Corner.Y=233|LineWidth=1|Color=16711680
|RECORD=6|OwnerIndex=1130|IsNotAccesible=T|IndexInSheet=10|OwnerPartId=1|LineWidth=1|Color=16711680|LocationCount=2|X1=1160|Y1=230|X2=1160|Y2=233
|RECORD=6|OwnerIndex=1130|IsNotAccesible=T|IndexInSheet=11|OwnerPartId=1|LineWidth=1|Color=16711680|LocationCount=2|X1=1160|Y1=240|X2=1160|Y2=237
|RECORD=41|OwnerIndex=1130|IndexInSheet=12|OwnerPartId=-1|Location.X=1151|Location.Y=252|Color=8388608|FontID=1|IsHidden=T|Text=Kemet|Name=Manufacturer
|RECORD=41|OwnerIndex=1130|IndexInSheet=13|OwnerPartId=-1|Location.X=1151|Location.Y=252|Color=8388608|FontID=1|IsHidden=T|Text=C0603X104K5RACAUTO|Name=Part Number
|RECORD=34|OwnerIndex=1130|IndexInSheet=-1|OwnerPartId=-1|Location.X=1169|Location.Y=231|Color=8388608|FontID=4|Text=C79|Name=Designator|ReadOnlyState=1
|RECORD=41|OwnerIndex=1130|IndexInSheet=-1|OwnerPartId=-1|Location.X=1169|Location.Y=221|Color=8388608|FontID=4|Text=0.1uF|Name=Comment
|RECORD=44|OwnerIndex=1130
|RECORD=45|OwnerIndex=1151|IndexInSheet=-1|Description=Chip Capacitor, 2-Leads, Body 1.60x0.80mm, IPC Low Density|UseComponentLibrary=T|ModelName=CAPC1608X87X45ML20T05|ModelType=PCBLIB|DatafileCount=1|ModelDatafileEntity0=CAPC1608X87X45ML20T05|ModelDatafileKind0=PCBLib|IsCurrent=T|DatalinksLocked=T|DatabaseDatalinksLocked=T
|RECORD=46|OwnerIndex=1152
|RECORD=48|OwnerIndex=1152
|RECORD=41|OwnerIndex=1154|IndexInSheet=-1|OwnerPartId=-1|Color=8388608|FontID=1|Text=2D|Name=Available Preview Images
|RECORD=45|OwnerIndex=1151|IndexInSheet=-1|Description=Chip Capacitor, 2-Leads, Body 1.60x0.80mm, IPC High Density|UseComponentLibrary=T|ModelName=CAPC1608X87X45LL20T05|ModelType=PCBLIB|DatafileCount=1|ModelDatafileEntity0=CAPC1608X87X45LL20T05|ModelDatafileKind0=PCBLib|DatalinksLocked=T|DatabaseDatalinksLocked=T
|RECORD=46|OwnerIndex=1156
|RECORD=48|OwnerIndex=1156
|RECORD=41|OwnerIndex=1158|IndexInSheet=-1|OwnerPartId=-1|Color=8388608|FontID=1|Text=2D|Name=Available Preview Images
|RECORD=45|OwnerIndex=1151|IndexInSheet=-1|Description=Chip Capacitor, 2-Leads, Body 1.60x0.80mm, IPC Medium Density|UseComponentLibrary=T|ModelName=CAPC1608X87X45NL20T05|ModelType=PCBLIB|DatafileCount=1|ModelDatafileEntity0=CAPC1608X87X45NL20T05|ModelDatafileKind0=PCBLib|DatalinksLocked=T|DatabaseDatalinksLocked=T
|RECORD=46|OwnerIndex=1160
|RECORD=48|OwnerIndex=1160
|RECORD=41|OwnerIndex=1162|IndexInSheet=-1|OwnerPartId=-1|Color=8388608|FontID=1|Text=2D|Name=Available Preview Images
|RECORD=1|LibReference=CAP|ComponentDescription=C0603X104K5RACAUTO|PartCount=2|DisplayModeCount=2|IndexInSheet=216|OwnerPartId=-1|Location.X=1190|Location.Y=230|Orientation=1|CurrentPartId=1|SourceLibraryName=Altium Content Vault|TargetFileName=*|AreaColor=11599871|Color=128|PartIDLocked=F|DesignItemId=CMP-2006-00003-1|AllPinCount=2
|RECORD=2|OwnerIndex=1164|OwnerPartId=1|OwnerPartDisplayMode=1|FormalType=1|Electrical=4|PinConglomerate=35|PinLength=10|Location.X=1200|Location.Y=230|Name=1|Designator=1|PinPropagationDelay=0.000000E+000
|RECORD=2|OwnerIndex=1164|OwnerPartId=1|OwnerPartDisplayMode=1|FormalType=1|Electrical=4|PinConglomerate=33|PinLength=10|Location.X=1200|Location.Y=240|Name=2|Designator=2|PinPropagationDelay=0.000000E+000
|RECORD=13|OwnerIndex=1164|IsNotAccesible=T|IndexInSheet=2|OwnerPartId=1|OwnerPartDisplayMode=1|Location.X=1208|Location.Y=230|Corner.X=1192|Corner.Y=230|LineWidth=1|Color=16711680
|RECORD=13|OwnerIndex=1164|IsNotAccesible=T|IndexInSheet=3|OwnerPartId=1|OwnerPartDisplayMode=1|Location.X=1200|Location.Y=234|Corner.X=1200|Corner.Y=240|LineWidth=1|Color=16711680
|RECORD=12|OwnerIndex=1164|IsNotAccesible=T|IndexInSheet=4|OwnerPartId=1|OwnerPartDisplayMode=1|Location.X=1200|Location.Y=250|Radius=16|LineWidth=1|StartAngle=241.000|EndAngle=270.000|Color=16711680
|RECORD=12|OwnerIndex=1164|IsNotAccesible=T|IndexInSheet=5|OwnerPartId=1|OwnerPartDisplayMode=1|Location.X=1200|Location.Y=250|Radius=16|LineWidth=1|StartAngle=270.000|EndAngle=299.000|Color=16711680
|RECORD=2|OwnerIndex=1164|OwnerPartId=1|FormalType=1|Electrical=4|PinConglomerate=35|PinLength=10|Location.X=1200|Location.Y=230|Name=1|Designator=1|PinPropagationDelay=0.000000E+000
|RECORD=2|OwnerIndex=1164|OwnerPartId=1|FormalType=1|Electrical=4|PinConglomerate=33|PinLength=10|Location.X=1200|Location.Y=240|Name=2|Designator=2|PinPropagationDelay=0.000000E+000
|RECORD=13|OwnerIndex=1164|IsNotAccesible=T|IndexInSheet=8|OwnerPartId=1|Location.X=1192|Location.Y=237|Corner.X=1208|Corner.Y=237|LineWidth=1|Color=16711680
|RECORD=13|OwnerIndex=1164|IsNotAccesible=T|IndexInSheet=9|OwnerPartId=1|Location.X=1208|Location.Y=233|Corner.X=1192|Corner.Y=233|LineWidth=1|Color=16711680
|RECORD=6|OwnerIndex=1164|IsNotAccesible=T|IndexInSheet=10|OwnerPartId=1|LineWidth=1|Color=16711680|LocationCount=2|X1=1200|Y1=230|X2=1200|Y2=233
|RECORD=6|OwnerIndex=1164|IsNotAccesible=T|IndexInSheet=11|OwnerPartId=1|LineWidth=1|Color=16711680|LocationCount=2|X1=1200|Y1=240|X2=1200|Y2=237
|RECORD=41|OwnerIndex=1164|IndexInSheet=12|OwnerPartId=-1|Location.X=1191|Location.Y=252|Color=8388608|FontID=1|IsHidden=T|Text=Kemet|Name=Manufacturer
|RECORD=41|OwnerIndex=1164|IndexInSheet=13|OwnerPartId=-1|Location.X=1191|Location.Y=252|Color=8388608|FontID=1|IsHidden=T|Text=C0603X104K5RACAUTO|Name=Part Number
|RECORD=34|OwnerIndex=1164|IndexInSheet=-1|OwnerPartId=-1|Location.X=1209|Location.Y=231|Color=8388608|FontID=4|Text=C80|Name=Designator|ReadOnlyState=1
|RECORD=41|OwnerIndex=1164|IndexInSheet=-1|OwnerPartId=-1|Location.X=1209|Location.Y=221|Color=8388608|FontID=4|Text=0.1uF|Name=Comment
|RECORD=44|OwnerIndex=1164
|RECORD=45|OwnerIndex=1185|IndexInSheet=-1|Description=Chip Capacitor, 2-Leads, Body 1.60x0.80mm, IPC Low Density|UseComponentLibrary=T|ModelName=CAPC1608X87X45ML20T05|ModelType=PCBLIB|DatafileCount=1|ModelDatafileEntity0=CAPC1608X87X45ML20T05|ModelDatafileKind0=PCBLib|IsCurrent=T|DatalinksLocked=T|DatabaseDatalinksLocked=T
|RECORD=46|OwnerIndex=1186
|RECORD=48|OwnerIndex=1186
|RECORD=41|OwnerIndex=1188|IndexInSheet=-1|OwnerPartId=-1|Color=8388608|FontID=1|Text=2D|Name=Available Preview Images
|RECORD=45|OwnerIndex=1185|IndexInSheet=-1|Description=Chip Capacitor, 2-Leads, Body 1.60x0.80mm, IPC High Density|UseComponentLibrary=T|ModelName=CAPC1608X87X45LL20T05|ModelType=PCBLIB|DatafileCount=1|ModelDatafileEntity0=CAPC1608X87X45LL20T05|ModelDatafileKind0=PCBLib|DatalinksLocked=T|DatabaseDatalinksLocked=T
|RECORD=46|OwnerIndex=1190
|RECORD=48|OwnerIndex=1190
|RECORD=41|OwnerIndex=1192|IndexInSheet=-1|OwnerPartId=-1|Color=8388608|FontID=1|Text=2D|Name=Available Preview Images
|RECORD=45|OwnerIndex=1185|IndexInSheet=-1|Description=Chip Capacitor, 2-Leads, Body 1.60x0.80mm, IPC Medium Density|UseComponentLibrary=T|ModelName=CAPC1608X87X45NL20T05|ModelType=PCBLIB|DatafileCount=1|ModelDatafileEntity0=CAPC1608X87X45NL20T05|ModelDatafileKind0=PCBLib|DatalinksLocked=T|DatabaseDatalinksLocked=T
|RECORD=46|OwnerIndex=1194
|RECORD=48|OwnerIndex=1194
|RECORD=41|OwnerIndex=1196|IndexInSheet=-1|OwnerPartId=-1|Color=8388608|FontID=1|Text=2D|Name=Available Preview Images
|RECORD=1|LibReference=CAP|ComponentDescription=C0603X104K5RACAUTO|PartCount=2|DisplayModeCount=2|IndexInSheet=217|OwnerPartId=-1|Location.X=1230|Location.Y=230|Orientation=1|CurrentPartId=1|SourceLibraryName=Altium Content Vault|TargetFileName=*|AreaColor=11599871|Color=128|PartIDLocked=F|DesignItemId=CMP-2006-00003-1|AllPinCount=2
|RECORD=2|OwnerIndex=1198|OwnerPartId=1|OwnerPartDisplayMode=1|FormalType=1|Electrical=4|PinConglomerate=35|PinLength=10|Location.X=1240|Location.Y=230|Name=1|Designator=1|PinPropagationDelay=0.000000E+000
|RECORD=2|OwnerIndex=1198|OwnerPartId=1|OwnerPartDisplayMode=1|FormalType=1|Electrical=4|PinConglomerate=33|PinLength=10|Location.X=1240|Location.Y=240|Name=2|Designator=2|PinPropagationDelay=0.000000E+000
|RECORD=13|OwnerIndex=1198|IsNotAccesible=T|IndexInSheet=2|OwnerPartId=1|OwnerPartDisplayMode=1|Location.X=1248|Location.Y=230|Corner.X=1232|Corner.Y=230|LineWidth=1|Color=16711680
|RECORD=13|OwnerIndex=1198|IsNotAccesible=T|IndexInSheet=3|OwnerPartId=1|OwnerPartDisplayMode=1|Location.X=1240|Location.Y=234|Corner.X=1240|Corner.Y=240|LineWidth=1|Color=16711680
|RECORD=12|OwnerIndex=1198|IsNotAccesible=T|IndexInSheet=4|OwnerPartId=1|OwnerPartDisplayMode=1|Location.X=1240|Location.Y=250|Radius=16|LineWidth=1|StartAngle=241.000|EndAngle=270.000|Color=16711680
|RECORD=12|OwnerIndex=1198|IsNotAccesible=T|IndexInSheet=5|OwnerPartId=1|OwnerPartDisplayMode=1|Location.X=1240|Location.Y=250|Radius=16|LineWidth=1|StartAngle=270.000|EndAngle=299.000|Color=16711680
|RECORD=2|OwnerIndex=1198|OwnerPartId=1|FormalType=1|Electrical=4|PinConglomerate=35|PinLength=10|Location.X=1240|Location.Y=230|Name=1|Designator=1|PinPropagationDelay=0.000000E+000
|RECORD=2|OwnerIndex=1198|OwnerPartId=1|FormalType=1|Electrical=4|PinConglomerate=33|PinLength=10|Location.X=1240|Location.Y=240|Name=2|Designator=2|PinPropagationDelay=0.000000E+000
|RECORD=13|OwnerIndex=1198|IsNotAccesible=T|IndexInSheet=8|OwnerPartId=1|Location.X=1232|Location.Y=237|Corner.X=1248|Corner.Y=237|LineWidth=1|Color=16711680
|RECORD=13|OwnerIndex=1198|IsNotAccesible=T|IndexInSheet=9|OwnerPartId=1|Location.X=1248|Location.Y=233|Corner.X=1232|Corner.Y=233|LineWidth=1|Color=16711680
|RECORD=6|OwnerIndex=1198|IsNotAccesible=T|IndexInSheet=10|OwnerPartId=1|LineWidth=1|Color=16711680|LocationCount=2|X1=1240|Y1=230|X2=1240|Y2=233
|RECORD=6|OwnerIndex=1198|IsNotAccesible=T|IndexInSheet=11|OwnerPartId=1|LineWidth=1|Color=16711680|LocationCount=2|X1=1240|Y1=240|X2=1240|Y2=237
|RECORD=41|OwnerIndex=1198|IndexInSheet=12|OwnerPartId=-1|Location.X=1231|Location.Y=252|Color=8388608|FontID=1|IsHidden=T|Text=Kemet|Name=Manufacturer
|RECORD=41|OwnerIndex=1198|IndexInSheet=13|OwnerPartId=-1|Location.X=1231|Location.Y=252|Color=8388608|FontID=1|IsHidden=T|Text=C0603X104K5RACAUTO|Name=Part Number
|RECORD=34|OwnerIndex=1198|IndexInSheet=-1|OwnerPartId=-1|Location.X=1249|Location.Y=231|Color=8388608|FontID=4|Text=C81|Name=Designator|ReadOnlyState=1
|RECORD=41|OwnerIndex=1198|IndexInSheet=-1|OwnerPartId=-1|Location.X=1249|Location.Y=221|Color=8388608|FontID=4|Text=0.1uF|Name=Comment
|RECORD=44|OwnerIndex=1198
|RECORD=45|OwnerIndex=1219|IndexInSheet=-1|Description=Chip Capacitor, 2-Leads, Body 1.60x0.80mm, IPC Low Density|UseComponentLibrary=T|ModelName=CAPC1608X87X45ML20T05|ModelType=PCBLIB|DatafileCount=1|ModelDatafileEntity0=CAPC1608X87X45ML20T05|ModelDatafileKind0=PCBLib|IsCurrent=T|DatalinksLocked=T|DatabaseDatalinksLocked=T
|RECORD=46|OwnerIndex=1220
|RECORD=48|OwnerIndex=1220
|RECORD=41|OwnerIndex=1222|IndexInSheet=-1|OwnerPartId=-1|Color=8388608|FontID=1|Text=2D|Name=Available Preview Images
|RECORD=45|OwnerIndex=1219|IndexInSheet=-1|Description=Chip Capacitor, 2-Leads, Body 1.60x0.80mm, IPC High Density|UseComponentLibrary=T|ModelName=CAPC1608X87X45LL20T05|ModelType=PCBLIB|DatafileCount=1|ModelDatafileEntity0=CAPC1608X87X45LL20T05|ModelDatafileKind0=PCBLib|DatalinksLocked=T|DatabaseDatalinksLocked=T
|RECORD=46|OwnerIndex=1224
|RECORD=48|OwnerIndex=1224
|RECORD=41|OwnerIndex=1226|IndexInSheet=-1|OwnerPartId=-1|Color=8388608|FontID=1|Text=2D|Name=Available Preview Images
|RECORD=45|OwnerIndex=1219|IndexInSheet=-1|Description=Chip Capacitor, 2-Leads, Body 1.60x0.80mm, IPC Medium Density|UseComponentLibrary=T|ModelName=CAPC1608X87X45NL20T05|ModelType=PCBLIB|DatafileCount=1|ModelDatafileEntity0=CAPC1608X87X45NL20T05|ModelDatafileKind0=PCBLib|DatalinksLocked=T|DatabaseDatalinksLocked=T
|RECORD=46|OwnerIndex=1228
|RECORD=48|OwnerIndex=1228
|RECORD=41|OwnerIndex=1230|IndexInSheet=-1|OwnerPartId=-1|Color=8388608|FontID=1|Text=2D|Name=Available Preview Images
|RECORD=1|LibReference=CAP|ComponentDescription=C0603X104K5RACAUTO|PartCount=2|DisplayModeCount=2|IndexInSheet=218|OwnerPartId=-1|Location.X=1270|Location.Y=230|Orientation=1|CurrentPartId=1|SourceLibraryName=Altium Content Vault|TargetFileName=*|AreaColor=11599871|Color=128|PartIDLocked=F|DesignItemId=CMP-2006-00003-1|AllPinCount=2
|RECORD=2|OwnerIndex=1232|OwnerPartId=1|OwnerPartDisplayMode=1|FormalType=1|Electrical=4|PinConglomerate=35|PinLength=10|Location.X=1280|Location.Y=230|Name=1|Designator=1|PinPropagationDelay=0.000000E+000
|RECORD=2|OwnerIndex=1232|OwnerPartId=1|OwnerPartDisplayMode=1|FormalType=1|Electrical=4|PinConglomerate=33|PinLength=10|Location.X=1280|Location.Y=240|Name=2|Designator=2|PinPropagationDelay=0.000000E+000
|RECORD=13|OwnerIndex=1232|IsNotAccesible=T|IndexInSheet=2|OwnerPartId=1|OwnerPartDisplayMode=1|Location.X=1288|Location.Y=230|Corner.X=1272|Corner.Y=230|LineWidth=1|Color=16711680
|RECORD=13|OwnerIndex=1232|IsNotAccesible=T|IndexInSheet=3|OwnerPartId=1|OwnerPartDisplayMode=1|Location.X=1280|Location.Y=234|Corner.X=1280|Corner.Y=240|LineWidth=1|Color=16711680
|RECORD=12|OwnerIndex=1232|IsNotAccesible=T|IndexInSheet=4|OwnerPartId=1|OwnerPartDisplayMode=1|Location.X=1280|Location.Y=250|Radius=16|LineWidth=1|StartAngle=241.000|EndAngle=270.000|Color=16711680
|RECORD=12|OwnerIndex=1232|IsNotAccesible=T|IndexInSheet=5|OwnerPartId=1|OwnerPartDisplayMode=1|Location.X=1280|Location.Y=250|Radius=16|LineWidth=1|StartAngle=270.000|EndAngle=299.000|Color=16711680
|RECORD=2|OwnerIndex=1232|OwnerPartId=1|FormalType=1|Electrical=4|PinConglomerate=35|PinLength=10|Location.X=1280|Location.Y=230|Name=1|Designator=1|PinPropagationDelay=0.000000E+000
|RECORD=2|OwnerIndex=1232|OwnerPartId=1|FormalType=1|Electrical=4|PinConglomerate=33|PinLength=10|Location.X=1280|Location.Y=240|Name=2|Designator=2|PinPropagationDelay=0.000000E+000
|RECORD=13|OwnerIndex=1232|IsNotAccesible=T|IndexInSheet=8|OwnerPartId=1|Location.X=1272|Location.Y=237|Corner.X=1288|Corner.Y=237|LineWidth=1|Color=16711680
|RECORD=13|OwnerIndex=1232|IsNotAccesible=T|IndexInSheet=9|OwnerPartId=1|Location.X=1288|Location.Y=233|Corner.X=1272|Corner.Y=233|LineWidth=1|Color=16711680
|RECORD=6|OwnerIndex=1232|IsNotAccesible=T|IndexInSheet=10|OwnerPartId=1|LineWidth=1|Color=16711680|LocationCount=2|X1=1280|Y1=230|X2=1280|Y2=233
|RECORD=6|OwnerIndex=1232|IsNotAccesible=T|IndexInSheet=11|OwnerPartId=1|LineWidth=1|Color=16711680|LocationCount=2|X1=1280|Y1=240|X2=1280|Y2=237
|RECORD=41|OwnerIndex=1232|IndexInSheet=12|OwnerPartId=-1|Location.X=1271|Location.Y=252|Color=8388608|FontID=1|IsHidden=T|Text=Kemet|Name=Manufacturer
|RECORD=41|OwnerIndex=1232|IndexInSheet=13|OwnerPartId=-1|Location.X=1271|Location.Y=252|Color=8388608|FontID=1|IsHidden=T|Text=C0603X104K5RACAUTO|Name=Part Number
|RECORD=34|OwnerIndex=1232|IndexInSheet=-1|OwnerPartId=-1|Location.X=1289|Location.Y=231|Color=8388608|FontID=4|Text=C82|Name=Designator|ReadOnlyState=1
|RECORD=41|OwnerIndex=1232|IndexInSheet=-1|OwnerPartId=-1|Location.X=1289|Location.Y=221|Color=8388608|FontID=4|Text=0.1uF|Name=Comment
|RECORD=44|OwnerIndex=1232
|RECORD=45|OwnerIndex=1253|IndexInSheet=-1|Description=Chip Capacitor, 2-Leads, Body 1.60x0.80mm, IPC Low Density|UseComponentLibrary=T|ModelName=CAPC1608X87X45ML20T05|ModelType=PCBLIB|DatafileCount=1|ModelDatafileEntity0=CAPC1608X87X45ML20T05|ModelDatafileKind0=PCBLib|IsCurrent=T|DatalinksLocked=T|DatabaseDatalinksLocked=T
|RECORD=46|OwnerIndex=1254
|RECORD=48|OwnerIndex=1254
|RECORD=41|OwnerIndex=1256|IndexInSheet=-1|OwnerPartId=-1|Color=8388608|FontID=1|Text=2D|Name=Available Preview Images
|RECORD=45|OwnerIndex=1253|IndexInSheet=-1|Description=Chip Capacitor, 2-Leads, Body 1.60x0.80mm, IPC High Density|UseComponentLibrary=T|ModelName=CAPC1608X87X45LL20T05|ModelType=PCBLIB|DatafileCount=1|ModelDatafileEntity0=CAPC1608X87X45LL20T05|ModelDatafileKind0=PCBLib|DatalinksLocked=T|DatabaseDatalinksLocked=T
|RECORD=46|OwnerIndex=1258
|RECORD=48|OwnerIndex=1258
|RECORD=41|OwnerIndex=1260|IndexInSheet=-1|OwnerPartId=-1|Color=8388608|FontID=1|Text=2D|Name=Available Preview Images
|RECORD=45|OwnerIndex=1253|IndexInSheet=-1|Description=Chip Capacitor, 2-Leads, Body 1.60x0.80mm, IPC Medium Density|UseComponentLibrary=T|ModelName=CAPC1608X87X45NL20T05|ModelType=PCBLIB|DatafileCount=1|ModelDatafileEntity0=CAPC1608X87X45NL20T05|ModelDatafileKind0=PCBLib|DatalinksLocked=T|DatabaseDatalinksLocked=T
|RECORD=46|OwnerIndex=1262
|RECORD=48|OwnerIndex=1262
|RECORD=41|OwnerIndex=1264|IndexInSheet=-1|OwnerPartId=-1|Color=8388608|FontID=1|Text=2D|Name=Available Preview Images
|RECORD=1|LibReference=CAP|ComponentDescription=C0603X104K5RACAUTO|PartCount=2|DisplayModeCount=2|IndexInSheet=219|OwnerPartId=-1|Location.X=1310|Location.Y=230|Orientation=1|CurrentPartId=1|SourceLibraryName=Altium Content Vault|TargetFileName=*|AreaColor=11599871|Color=128|PartIDLocked=F|DesignItemId=CMP-2006-00003-1|AllPinCount=2
|RECORD=2|OwnerIndex=1266|OwnerPartId=1|OwnerPartDisplayMode=1|FormalType=1|Electrical=4|PinConglomerate=35|PinLength=10|Location.X=1320|Location.Y=230|Name=1|Designator=1|PinPropagationDelay=0.000000E+000
|RECORD=2|OwnerIndex=1266|OwnerPartId=1|OwnerPartDisplayMode=1|FormalType=1|Electrical=4|PinConglomerate=33|PinLength=10|Location.X=1320|Location.Y=240|Name=2|Designator=2|PinPropagationDelay=0.000000E+000
|RECORD=13|OwnerIndex=1266|IsNotAccesible=T|IndexInSheet=2|OwnerPartId=1|OwnerPartDisplayMode=1|Location.X=1328|Location.Y=230|Corner.X=1312|Corner.Y=230|LineWidth=1|Color=16711680
|RECORD=13|OwnerIndex=1266|IsNotAccesible=T|IndexInSheet=3|OwnerPartId=1|OwnerPartDisplayMode=1|Location.X=1320|Location.Y=234|Corner.X=1320|Corner.Y=240|LineWidth=1|Color=16711680
|RECORD=12|OwnerIndex=1266|IsNotAccesible=T|IndexInSheet=4|OwnerPartId=1|OwnerPartDisplayMode=1|Location.X=1320|Location.Y=250|Radius=16|LineWidth=1|StartAngle=241.000|EndAngle=270.000|Color=16711680
|RECORD=12|OwnerIndex=1266|IsNotAccesible=T|IndexInSheet=5|OwnerPartId=1|OwnerPartDisplayMode=1|Location.X=1320|Location.Y=250|Radius=16|LineWidth=1|StartAngle=270.000|EndAngle=299.000|Color=16711680
|RECORD=2|OwnerIndex=1266|OwnerPartId=1|FormalType=1|Electrical=4|PinConglomerate=35|PinLength=10|Location.X=1320|Location.Y=230|Name=1|Designator=1|PinPropagationDelay=0.000000E+000
|RECORD=2|OwnerIndex=1266|OwnerPartId=1|FormalType=1|Electrical=4|PinConglomerate=33|PinLength=10|Location.X=1320|Location.Y=240|Name=2|Designator=2|PinPropagationDelay=0.000000E+000
|RECORD=13|OwnerIndex=1266|IsNotAccesible=T|IndexInSheet=8|OwnerPartId=1|Location.X=1312|Location.Y=237|Corner.X=1328|Corner.Y=237|LineWidth=1|Color=16711680
|RECORD=13|OwnerIndex=1266|IsNotAccesible=T|IndexInSheet=9|OwnerPartId=1|Location.X=1328|Location.Y=233|Corner.X=1312|Corner.Y=233|LineWidth=1|Color=16711680
|RECORD=6|OwnerIndex=1266|IsNotAccesible=T|IndexInSheet=10|OwnerPartId=1|LineWidth=1|Color=16711680|LocationCount=2|X1=1320|Y1=230|X2=1320|Y2=233
|RECORD=6|OwnerIndex=1266|IsNotAccesible=T|IndexInSheet=11|OwnerPartId=1|LineWidth=1|Color=16711680|LocationCount=2|X1=1320|Y1=240|X2=1320|Y2=237
|RECORD=41|OwnerIndex=1266|IndexInSheet=12|OwnerPartId=-1|Location.X=1311|Location.Y=252|Color=8388608|FontID=1|IsHidden=T|Text=Kemet|Name=Manufacturer
|RECORD=41|OwnerIndex=1266|IndexInSheet=13|OwnerPartId=-1|Location.X=1311|Location.Y=252|Color=8388608|FontID=1|IsHidden=T|Text=C0603X104K5RACAUTO|Name=Part Number
|RECORD=34|OwnerIndex=1266|IndexInSheet=-1|OwnerPartId=-1|Location.X=1329|Location.Y=231|Color=8388608|FontID=4|Text=C83|Name=Designator|ReadOnlyState=1
|RECORD=41|OwnerIndex=1266|IndexInSheet=-1|OwnerPartId=-1|Location.X=1329|Location.Y=221|Color=8388608|FontID=4|Text=0.1uF|Name=Comment
|RECORD=44|OwnerIndex=1266
|RECORD=45|OwnerIndex=1287|IndexInSheet=-1|Description=Chip Capacitor, 2-Leads, Body 1.60x0.80mm, IPC Low Density|UseComponentLibrary=T|ModelName=CAPC1608X87X45ML20T05|ModelType=PCBLIB|DatafileCount=1|ModelDatafileEntity0=CAPC1608X87X45ML20T05|ModelDatafileKind0=PCBLib|IsCurrent=T|DatalinksLocked=T|DatabaseDatalinksLocked=T
|RECORD=46|OwnerIndex=1288
|RECORD=48|OwnerIndex=1288
|RECORD=41|OwnerIndex=1290|IndexInSheet=-1|OwnerPartId=-1|Color=8388608|FontID=1|Text=2D|Name=Available Preview Images
|RECORD=45|OwnerIndex=1287|IndexInSheet=-1|Description=Chip Capacitor, 2-Leads, Body 1.60x0.80mm, IPC High Density|UseComponentLibrary=T|ModelName=CAPC1608X87X45LL20T05|ModelType=PCBLIB|DatafileCount=1|ModelDatafileEntity0=CAPC1608X87X45LL20T05|ModelDatafileKind0=PCBLib|DatalinksLocked=T|DatabaseDatalinksLocked=T
|RECORD=46|OwnerIndex=1292
|RECORD=48|OwnerIndex=1292
|RECORD=41|OwnerIndex=1294|IndexInSheet=-1|OwnerPartId=-1|Color=8388608|FontID=1|Text=2D|Name=Available Preview Images
|RECORD=45|OwnerIndex=1287|IndexInSheet=-1|Description=Chip Capacitor, 2-Leads, Body 1.60x0.80mm, IPC Medium Density|UseComponentLibrary=T|ModelName=CAPC1608X87X45NL20T05|ModelType=PCBLIB|DatafileCount=1|ModelDatafileEntity0=CAPC1608X87X45NL20T05|ModelDatafileKind0=PCBLib|DatalinksLocked=T|DatabaseDatalinksLocked=T
|RECORD=46|OwnerIndex=1296
|RECORD=48|OwnerIndex=1296
|RECORD=41|OwnerIndex=1298|IndexInSheet=-1|OwnerPartId=-1|Color=8388608|FontID=1|Text=2D|Name=Available Preview Images
|RECORD=1|LibReference=CAP|ComponentDescription=C0603X104K5RACAUTO|PartCount=2|DisplayModeCount=2|IndexInSheet=220|OwnerPartId=-1|Location.X=710|Location.Y=370|Orientation=1|CurrentPartId=1|SourceLibraryName=Altium Content Vault|TargetFileName=*|AreaColor=11599871|Color=128|PartIDLocked=F|DesignItemId=CMP-2006-00003-1|AllPinCount=2
|RECORD=2|OwnerIndex=1300|OwnerPartId=1|OwnerPartDisplayMode=1|FormalType=1|Electrical=4|PinConglomerate=35|PinLength=10|Location.X=720|Location.Y=370|Name=1|Designator=1|PinPropagationDelay=0.000000E+000
|RECORD=2|OwnerIndex=1300|OwnerPartId=1|OwnerPartDisplayMode=1|FormalType=1|Electrical=4|PinConglomerate=33|PinLength=10|Location.X=720|Location.Y=380|Name=2|Designator=2|PinPropagationDelay=0.000000E+000
|RECORD=13|OwnerIndex=1300|IsNotAccesible=T|IndexInSheet=2|OwnerPartId=1|OwnerPartDisplayMode=1|Location.X=728|Location.Y=370|Corner.X=712|Corner.Y=370|LineWidth=1|Color=16711680
|RECORD=13|OwnerIndex=1300|IsNotAccesible=T|IndexInSheet=3|OwnerPartId=1|OwnerPartDisplayMode=1|Location.X=720|Location.Y=374|Corner.X=720|Corner.Y=380|LineWidth=1|Color=16711680
|RECORD=12|OwnerIndex=1300|IsNotAccesible=T|IndexInSheet=4|OwnerPartId=1|OwnerPartDisplayMode=1|Location.X=720|Location.Y=390|Radius=16|LineWidth=1|StartAngle=241.000|EndAngle=270.000|Color=16711680
|RECORD=12|OwnerIndex=1300|IsNotAccesible=T|IndexInSheet=5|OwnerPartId=1|OwnerPartDisplayMode=1|Location.X=720|Location.Y=390|Radius=16|LineWidth=1|StartAngle=270.000|EndAngle=299.000|Color=16711680
|RECORD=2|OwnerIndex=1300|OwnerPartId=1|FormalType=1|Electrical=4|PinConglomerate=35|PinLength=10|Location.X=720|Location.Y=370|Name=1|Designator=1|PinPropagationDelay=0.000000E+000
|RECORD=2|OwnerIndex=1300|OwnerPartId=1|FormalType=1|Electrical=4|PinConglomerate=33|PinLength=10|Location.X=720|Location.Y=380|Name=2|Designator=2|PinPropagationDelay=0.000000E+000
|RECORD=13|OwnerIndex=1300|IsNotAccesible=T|IndexInSheet=8|OwnerPartId=1|Location.X=712|Location.Y=377|Corner.X=728|Corner.Y=377|LineWidth=1|Color=16711680
|RECORD=13|OwnerIndex=1300|IsNotAccesible=T|IndexInSheet=9|OwnerPartId=1|Location.X=728|Location.Y=373|Corner.X=712|Corner.Y=373|LineWidth=1|Color=16711680
|RECORD=6|OwnerIndex=1300|IsNotAccesible=T|IndexInSheet=10|OwnerPartId=1|LineWidth=1|Color=16711680|LocationCount=2|X1=720|Y1=370|X2=720|Y2=373
|RECORD=6|OwnerIndex=1300|IsNotAccesible=T|IndexInSheet=11|OwnerPartId=1|LineWidth=1|Color=16711680|LocationCount=2|X1=720|Y1=380|X2=720|Y2=377
|RECORD=41|OwnerIndex=1300|IndexInSheet=12|OwnerPartId=-1|Location.X=711|Location.Y=392|Color=8388608|FontID=1|IsHidden=T|Text=Kemet|Name=Manufacturer
|RECORD=41|OwnerIndex=1300|IndexInSheet=13|OwnerPartId=-1|Location.X=711|Location.Y=392|Color=8388608|FontID=1|IsHidden=T|Text=C0603X104K5RACAUTO|Name=Part Number
|RECORD=34|OwnerIndex=1300|IndexInSheet=-1|OwnerPartId=-1|Location.X=729|Location.Y=371|Color=8388608|FontID=4|Text=C63|Name=Designator|ReadOnlyState=1
|RECORD=41|OwnerIndex=1300|IndexInSheet=-1|OwnerPartId=-1|Location.X=729|Location.Y=361|Color=8388608|FontID=4|Text=0.1uF|Name=Comment
|RECORD=44|OwnerIndex=1300
|RECORD=45|OwnerIndex=1321|IndexInSheet=-1|Description=Chip Capacitor, 2-Leads, Body 1.60x0.80mm, IPC Low Density|UseComponentLibrary=T|ModelName=CAPC1608X87X45ML20T05|ModelType=PCBLIB|DatafileCount=1|ModelDatafileEntity0=CAPC1608X87X45ML20T05|ModelDatafileKind0=PCBLib|IsCurrent=T|DatalinksLocked=T|DatabaseDatalinksLocked=T
|RECORD=46|OwnerIndex=1322
|RECORD=48|OwnerIndex=1322
|RECORD=41|OwnerIndex=1324|IndexInSheet=-1|OwnerPartId=-1|Color=8388608|FontID=1|Text=2D|Name=Available Preview Images
|RECORD=45|OwnerIndex=1321|IndexInSheet=-1|Description=Chip Capacitor, 2-Leads, Body 1.60x0.80mm, IPC High Density|UseComponentLibrary=T|ModelName=CAPC1608X87X45LL20T05|ModelType=PCBLIB|DatafileCount=1|ModelDatafileEntity0=CAPC1608X87X45LL20T05|ModelDatafileKind0=PCBLib|DatalinksLocked=T|DatabaseDatalinksLocked=T
|RECORD=46|OwnerIndex=1326
|RECORD=48|OwnerIndex=1326
|RECORD=41|OwnerIndex=1328|IndexInSheet=-1|OwnerPartId=-1|Color=8388608|FontID=1|Text=2D|Name=Available Preview Images
|RECORD=45|OwnerIndex=1321|IndexInSheet=-1|Description=Chip Capacitor, 2-Leads, Body 1.60x0.80mm, IPC Medium Density|UseComponentLibrary=T|ModelName=CAPC1608X87X45NL20T05|ModelType=PCBLIB|DatafileCount=1|ModelDatafileEntity0=CAPC1608X87X45NL20T05|ModelDatafileKind0=PCBLib|DatalinksLocked=T|DatabaseDatalinksLocked=T
|RECORD=46|OwnerIndex=1330
|RECORD=48|OwnerIndex=1330
|RECORD=41|OwnerIndex=1332|IndexInSheet=-1|OwnerPartId=-1|Color=8388608|FontID=1|Text=2D|Name=Available Preview Images
|RECORD=41|IndexInSheet=221|OwnerPartId=-1|Color=8388608|FontID=1|IsHidden=T|Name=ConfigurationParameters|ReadOnlyState=1
|RECORD=41|IndexInSheet=222|OwnerPartId=-1|Color=8388608|FontID=1|IsHidden=T|Name=ConfiguratorName|ReadOnlyState=1
|RECORD=41|IndexInSheet=223|OwnerPartId=-1|Color=8388608|FontID=1|IsHidden=T|Name=VersionControl_RevNumber|ReadOnlyState=1
|RECORD=41|IndexInSheet=224|OwnerPartId=-1|Color=8388608|FontID=1|IsHidden=T|Name=IsUserConfigurable|ReadOnlyState=1
|RECORD=41|IndexInSheet=225|OwnerPartId=-1|Color=8388608|FontID=1|IsHidden=T|Name=VersionControl_ProjFolderRevNumber|ReadOnlyState=1
|RECORD=41|IndexInSheet=226|OwnerPartId=-1|Color=8388608|FontID=1|IsHidden=T|Name=SPICEModelCache|ReadOnlyState=1
|RECORD=29|IndexInSheet=-1|OwnerPartId=-1|Location.X=310|Location.Y=410|Color=128
|RECORD=29|IndexInSheet=-1|OwnerPartId=-1|Location.X=320|Location.Y=400|Color=128
|RECORD=29|IndexInSheet=-1|OwnerPartId=-1|Location.X=340|Location.Y=590|Color=128
|RECORD=29|IndexInSheet=-1|OwnerPartId=-1|Location.X=550|Location.Y=220|Color=128
|RECORD=29|IndexInSheet=-1|OwnerPartId=-1|Location.X=550|Location.Y=230|Color=128
|RECORD=29|IndexInSheet=-1|OwnerPartId=-1|Location.X=550|Location.Y=570|Color=128
|RECORD=29|IndexInSheet=-1|OwnerPartId=-1|Location.X=670|Location.Y=400|Color=128
|RECORD=29|IndexInSheet=-1|OwnerPartId=-1|Location.X=720|Location.Y=350|Color=128
|RECORD=29|IndexInSheet=-1|OwnerPartId=-1|Location.X=720|Location.Y=400|Color=128
|RECORD=29|IndexInSheet=-1|OwnerPartId=-1|Location.X=1040|Location.Y=210|Color=128
|RECORD=29|IndexInSheet=-1|OwnerPartId=-1|Location.X=1040|Location.Y=260|Color=128
|RECORD=29|IndexInSheet=-1|OwnerPartId=-1|Location.X=1080|Location.Y=210|Color=128
|RECORD=29|IndexInSheet=-1|OwnerPartId=-1|Location.X=1080|Location.Y=260|Color=128
|RECORD=29|IndexInSheet=-1|OwnerPartId=-1|Location.X=1120|Location.Y=210|Color=128
|RECORD=29|IndexInSheet=-1|OwnerPartId=-1|Location.X=1120|Location.Y=260|Color=128
|RECORD=29|IndexInSheet=-1|OwnerPartId=-1|Location.X=1140|Location.Y=400|Color=128
|RECORD=29|IndexInSheet=-1|OwnerPartId=-1|Location.X=1160|Location.Y=210|Color=128
|RECORD=29|IndexInSheet=-1|OwnerPartId=-1|Location.X=1160|Location.Y=260|Color=128
|RECORD=29|IndexInSheet=-1|OwnerPartId=-1|Location.X=1180|Location.Y=350|Color=128
|RECORD=29|IndexInSheet=-1|OwnerPartId=-1|Location.X=1180|Location.Y=400|Color=128
|RECORD=29|IndexInSheet=-1|OwnerPartId=-1|Location.X=1200|Location.Y=210|Color=128
|RECORD=29|IndexInSheet=-1|OwnerPartId=-1|Location.X=1200|Location.Y=260|Color=128
|RECORD=29|IndexInSheet=-1|OwnerPartId=-1|Location.X=1220|Location.Y=710|Color=128
|RECORD=29|IndexInSheet=-1|OwnerPartId=-1|Location.X=1240|Location.Y=210|Color=128
|RECORD=29|IndexInSheet=-1|OwnerPartId=-1|Location.X=1240|Location.Y=260|Color=128
|RECORD=29|IndexInSheet=-1|OwnerPartId=-1|Location.X=1240|Location.Y=350|Color=128
|RECORD=29|IndexInSheet=-1|OwnerPartId=-1|Location.X=1260|Location.Y=660|Color=128
|RECORD=29|IndexInSheet=-1|OwnerPartId=-1|Location.X=1260|Location.Y=710|Color=128
|RECORD=29|IndexInSheet=-1|OwnerPartId=-1|Location.X=1280|Location.Y=210|Color=128
|RECORD=29|IndexInSheet=-1|OwnerPartId=-1|Location.X=1280|Location.Y=260|Color=128
|RECORD=29|IndexInSheet=-1|OwnerPartId=-1|Location.X=1300|Location.Y=350|Color=128
|RECORD=29|IndexInSheet=-1|OwnerPartId=-1|Location.X=1300|Location.Y=400|Color=128
|RECORD=29|IndexInSheet=-1|OwnerPartId=-1|Location.X=1300|Location.Y=660|Color=128
|RECORD=29|IndexInSheet=-1|OwnerPartId=-1|Location.X=1300|Location.Y=710|Color=128
|RECORD=29|IndexInSheet=-1|OwnerPartId=-1|Location.X=1320|Location.Y=210|Color=128
|RECORD=29|IndexInSheet=-1|OwnerPartId=-1|Location.X=1320|Location.Y=260|Color=128
|RECORD=29|IndexInSheet=-1|OwnerPartId=-1|Location.X=1350|Location.Y=400|Color=128